G04*
G04 #@! TF.GenerationSoftware,Altium Limited,Altium Designer,23.0.1 (38)*
G04*
G04 Layer_Color=16711935*
%FSLAX25Y25*%
%MOIN*%
G70*
G04*
G04 #@! TF.SameCoordinates,C48E81DB-6E20-4E2D-80E6-7C5AFAA1A21F*
G04*
G04*
G04 #@! TF.FilePolarity,Positive*
G04*
G01*
G75*
%ADD15C,0.00787*%
%ADD16C,0.00394*%
%ADD18C,0.00300*%
%ADD21C,0.00100*%
G36*
X603109Y-331928D02*
Y-331931D01*
Y-331946D01*
Y-331965D01*
Y-331991D01*
X603105Y-332024D01*
Y-332061D01*
X603102Y-332105D01*
X603098Y-332150D01*
X603087Y-332249D01*
X603072Y-332353D01*
X603050Y-332453D01*
X603035Y-332501D01*
X603020Y-332545D01*
Y-332549D01*
X603017Y-332557D01*
X603009Y-332568D01*
X603002Y-332582D01*
X602980Y-332623D01*
X602946Y-332675D01*
X602902Y-332734D01*
X602850Y-332793D01*
X602783Y-332856D01*
X602702Y-332912D01*
X602698D01*
X602691Y-332919D01*
X602680Y-332923D01*
X602661Y-332934D01*
X602639Y-332945D01*
X602609Y-332956D01*
X602580Y-332967D01*
X602543Y-332982D01*
X602502Y-332997D01*
X602458Y-333008D01*
X602410Y-333019D01*
X602354Y-333030D01*
X602299Y-333038D01*
X602240Y-333045D01*
X602106Y-333052D01*
X602073D01*
X602047Y-333049D01*
X602017D01*
X601980Y-333045D01*
X601940Y-333041D01*
X601899Y-333038D01*
X601807Y-333023D01*
X601707Y-333001D01*
X601611Y-332971D01*
X601518Y-332930D01*
X601514D01*
X601507Y-332923D01*
X601496Y-332915D01*
X601481Y-332908D01*
X601440Y-332878D01*
X601392Y-332838D01*
X601337Y-332786D01*
X601285Y-332727D01*
X601233Y-332653D01*
X601192Y-332571D01*
Y-332568D01*
X601189Y-332560D01*
X601185Y-332545D01*
X601178Y-332527D01*
X601170Y-332505D01*
X601163Y-332475D01*
X601152Y-332442D01*
X601144Y-332401D01*
X601137Y-332357D01*
X601126Y-332309D01*
X601118Y-332257D01*
X601111Y-332201D01*
X601104Y-332138D01*
X601100Y-332072D01*
X601096Y-332002D01*
Y-331928D01*
Y-330448D01*
X601437D01*
Y-331928D01*
Y-331931D01*
Y-331942D01*
Y-331961D01*
Y-331983D01*
X601440Y-332009D01*
Y-332042D01*
X601444Y-332113D01*
X601451Y-332194D01*
X601463Y-332275D01*
X601477Y-332353D01*
X601485Y-332386D01*
X601496Y-332420D01*
X601500Y-332427D01*
X601507Y-332446D01*
X601525Y-332471D01*
X601548Y-332508D01*
X601574Y-332545D01*
X601611Y-332586D01*
X601655Y-332627D01*
X601707Y-332660D01*
X601714Y-332664D01*
X601733Y-332675D01*
X601766Y-332686D01*
X601810Y-332701D01*
X601862Y-332719D01*
X601929Y-332731D01*
X601999Y-332742D01*
X602077Y-332745D01*
X602114D01*
X602136Y-332742D01*
X602169D01*
X602203Y-332738D01*
X602284Y-332723D01*
X602373Y-332705D01*
X602458Y-332675D01*
X602539Y-332634D01*
X602576Y-332608D01*
X602609Y-332579D01*
X602613Y-332575D01*
X602617Y-332571D01*
X602624Y-332560D01*
X602635Y-332545D01*
X602646Y-332523D01*
X602661Y-332501D01*
X602676Y-332468D01*
X602691Y-332435D01*
X602706Y-332394D01*
X602717Y-332346D01*
X602732Y-332290D01*
X602743Y-332231D01*
X602754Y-332164D01*
X602761Y-332094D01*
X602769Y-332013D01*
Y-331928D01*
Y-330448D01*
X603109D01*
Y-331928D01*
D02*
G37*
G36*
X605122Y-330781D02*
X604097D01*
X603960Y-331472D01*
X603964Y-331469D01*
X603971Y-331465D01*
X603982Y-331458D01*
X604001Y-331447D01*
X604023Y-331435D01*
X604049Y-331421D01*
X604108Y-331391D01*
X604182Y-331362D01*
X604263Y-331336D01*
X604352Y-331317D01*
X604397Y-331310D01*
X604478D01*
X604500Y-331313D01*
X604530Y-331317D01*
X604563Y-331321D01*
X604600Y-331328D01*
X604641Y-331339D01*
X604730Y-331365D01*
X604778Y-331384D01*
X604826Y-331410D01*
X604874Y-331435D01*
X604922Y-331465D01*
X604966Y-331502D01*
X605011Y-331543D01*
X605015Y-331546D01*
X605022Y-331554D01*
X605033Y-331565D01*
X605048Y-331583D01*
X605066Y-331609D01*
X605085Y-331635D01*
X605107Y-331669D01*
X605129Y-331706D01*
X605148Y-331746D01*
X605170Y-331791D01*
X605188Y-331842D01*
X605207Y-331894D01*
X605222Y-331950D01*
X605233Y-332013D01*
X605240Y-332076D01*
X605244Y-332142D01*
Y-332146D01*
Y-332157D01*
Y-332175D01*
X605240Y-332201D01*
X605236Y-332231D01*
X605233Y-332264D01*
X605225Y-332305D01*
X605218Y-332346D01*
X605196Y-332442D01*
X605159Y-332542D01*
X605137Y-332594D01*
X605107Y-332642D01*
X605077Y-332694D01*
X605040Y-332742D01*
X605037Y-332745D01*
X605029Y-332756D01*
X605015Y-332771D01*
X604996Y-332790D01*
X604970Y-332812D01*
X604941Y-332841D01*
X604904Y-332867D01*
X604863Y-332897D01*
X604818Y-332927D01*
X604767Y-332952D01*
X604711Y-332978D01*
X604652Y-333004D01*
X604589Y-333023D01*
X604519Y-333038D01*
X604445Y-333049D01*
X604367Y-333052D01*
X604334D01*
X604308Y-333049D01*
X604278Y-333045D01*
X604245Y-333041D01*
X604204Y-333038D01*
X604164Y-333027D01*
X604071Y-333004D01*
X603978Y-332971D01*
X603930Y-332949D01*
X603882Y-332923D01*
X603838Y-332893D01*
X603793Y-332860D01*
X603790Y-332856D01*
X603782Y-332853D01*
X603775Y-332838D01*
X603760Y-332823D01*
X603742Y-332804D01*
X603723Y-332782D01*
X603701Y-332753D01*
X603683Y-332719D01*
X603660Y-332686D01*
X603638Y-332645D01*
X603597Y-332557D01*
X603564Y-332453D01*
X603553Y-332398D01*
X603546Y-332338D01*
X603875Y-332312D01*
Y-332316D01*
Y-332324D01*
X603879Y-332335D01*
X603882Y-332353D01*
X603893Y-332394D01*
X603908Y-332449D01*
X603930Y-332505D01*
X603960Y-332568D01*
X603997Y-332623D01*
X604041Y-332675D01*
X604049Y-332679D01*
X604064Y-332694D01*
X604093Y-332712D01*
X604134Y-332734D01*
X604178Y-332756D01*
X604234Y-332775D01*
X604297Y-332790D01*
X604367Y-332793D01*
X604389D01*
X604404Y-332790D01*
X604448Y-332786D01*
X604500Y-332771D01*
X604563Y-332753D01*
X604626Y-332723D01*
X604693Y-332679D01*
X604722Y-332653D01*
X604752Y-332623D01*
X604755Y-332620D01*
X604759Y-332616D01*
X604767Y-332605D01*
X604778Y-332594D01*
X604804Y-332553D01*
X604833Y-332501D01*
X604859Y-332438D01*
X604885Y-332361D01*
X604904Y-332268D01*
X604911Y-332220D01*
Y-332168D01*
Y-332164D01*
Y-332157D01*
Y-332142D01*
X604907Y-332124D01*
Y-332101D01*
X604904Y-332076D01*
X604892Y-332016D01*
X604874Y-331946D01*
X604848Y-331876D01*
X604811Y-331809D01*
X604759Y-331746D01*
Y-331743D01*
X604752Y-331739D01*
X604733Y-331720D01*
X604700Y-331695D01*
X604656Y-331665D01*
X604596Y-331639D01*
X604530Y-331613D01*
X604452Y-331595D01*
X604408Y-331587D01*
X604337D01*
X604308Y-331591D01*
X604271Y-331595D01*
X604226Y-331606D01*
X604182Y-331617D01*
X604134Y-331635D01*
X604086Y-331658D01*
X604082Y-331661D01*
X604067Y-331669D01*
X604045Y-331687D01*
X604015Y-331706D01*
X603986Y-331732D01*
X603956Y-331765D01*
X603923Y-331798D01*
X603897Y-331839D01*
X603601Y-331798D01*
X603849Y-330481D01*
X605122D01*
Y-330781D01*
D02*
G37*
G36*
X521581Y-330768D02*
X520556D01*
X520419Y-331460D01*
X520423Y-331457D01*
X520430Y-331453D01*
X520441Y-331446D01*
X520460Y-331434D01*
X520482Y-331423D01*
X520508Y-331409D01*
X520567Y-331379D01*
X520641Y-331349D01*
X520722Y-331324D01*
X520811Y-331305D01*
X520855Y-331298D01*
X520937D01*
X520959Y-331301D01*
X520989Y-331305D01*
X521022Y-331309D01*
X521059Y-331316D01*
X521100Y-331327D01*
X521188Y-331353D01*
X521237Y-331372D01*
X521285Y-331398D01*
X521333Y-331423D01*
X521381Y-331453D01*
X521425Y-331490D01*
X521470Y-331531D01*
X521473Y-331534D01*
X521481Y-331542D01*
X521492Y-331553D01*
X521507Y-331571D01*
X521525Y-331597D01*
X521544Y-331623D01*
X521566Y-331657D01*
X521588Y-331694D01*
X521606Y-331734D01*
X521629Y-331779D01*
X521647Y-331830D01*
X521666Y-331882D01*
X521680Y-331938D01*
X521692Y-332001D01*
X521699Y-332064D01*
X521703Y-332130D01*
Y-332134D01*
Y-332145D01*
Y-332163D01*
X521699Y-332189D01*
X521695Y-332219D01*
X521692Y-332252D01*
X521684Y-332293D01*
X521677Y-332334D01*
X521655Y-332430D01*
X521618Y-332530D01*
X521595Y-332581D01*
X521566Y-332630D01*
X521536Y-332681D01*
X521499Y-332730D01*
X521495Y-332733D01*
X521488Y-332744D01*
X521473Y-332759D01*
X521455Y-332778D01*
X521429Y-332800D01*
X521399Y-332829D01*
X521362Y-332855D01*
X521322Y-332885D01*
X521277Y-332914D01*
X521225Y-332940D01*
X521170Y-332966D01*
X521111Y-332992D01*
X521048Y-333011D01*
X520977Y-333026D01*
X520903Y-333037D01*
X520826Y-333040D01*
X520792D01*
X520767Y-333037D01*
X520737Y-333033D01*
X520704Y-333029D01*
X520663Y-333026D01*
X520622Y-333014D01*
X520530Y-332992D01*
X520437Y-332959D01*
X520389Y-332937D01*
X520341Y-332911D01*
X520297Y-332881D01*
X520252Y-332848D01*
X520249Y-332844D01*
X520241Y-332840D01*
X520234Y-332826D01*
X520219Y-332811D01*
X520200Y-332792D01*
X520182Y-332770D01*
X520160Y-332741D01*
X520141Y-332707D01*
X520119Y-332674D01*
X520097Y-332633D01*
X520056Y-332544D01*
X520023Y-332441D01*
X520012Y-332385D01*
X520004Y-332326D01*
X520334Y-332300D01*
Y-332304D01*
Y-332311D01*
X520337Y-332323D01*
X520341Y-332341D01*
X520352Y-332382D01*
X520367Y-332437D01*
X520389Y-332493D01*
X520419Y-332556D01*
X520456Y-332611D01*
X520500Y-332663D01*
X520508Y-332667D01*
X520522Y-332681D01*
X520552Y-332700D01*
X520593Y-332722D01*
X520637Y-332744D01*
X520693Y-332763D01*
X520755Y-332778D01*
X520826Y-332781D01*
X520848D01*
X520863Y-332778D01*
X520907Y-332774D01*
X520959Y-332759D01*
X521022Y-332741D01*
X521085Y-332711D01*
X521151Y-332667D01*
X521181Y-332641D01*
X521211Y-332611D01*
X521214Y-332607D01*
X521218Y-332604D01*
X521225Y-332593D01*
X521237Y-332581D01*
X521262Y-332541D01*
X521292Y-332489D01*
X521318Y-332426D01*
X521344Y-332348D01*
X521362Y-332256D01*
X521370Y-332208D01*
Y-332156D01*
Y-332152D01*
Y-332145D01*
Y-332130D01*
X521366Y-332112D01*
Y-332089D01*
X521362Y-332064D01*
X521351Y-332004D01*
X521333Y-331934D01*
X521307Y-331864D01*
X521270Y-331797D01*
X521218Y-331734D01*
Y-331731D01*
X521211Y-331727D01*
X521192Y-331708D01*
X521159Y-331682D01*
X521114Y-331653D01*
X521055Y-331627D01*
X520989Y-331601D01*
X520911Y-331582D01*
X520866Y-331575D01*
X520796D01*
X520767Y-331579D01*
X520730Y-331582D01*
X520685Y-331594D01*
X520641Y-331605D01*
X520593Y-331623D01*
X520545Y-331645D01*
X520541Y-331649D01*
X520526Y-331657D01*
X520504Y-331675D01*
X520474Y-331694D01*
X520445Y-331719D01*
X520415Y-331753D01*
X520382Y-331786D01*
X520356Y-331827D01*
X520060Y-331786D01*
X520308Y-330469D01*
X521581D01*
Y-330768D01*
D02*
G37*
G36*
X518602Y-330439D02*
X518676Y-330443D01*
X518750Y-330450D01*
X518824Y-330461D01*
X518887Y-330472D01*
X518891D01*
X518898Y-330476D01*
X518909D01*
X518924Y-330484D01*
X518965Y-330495D01*
X519017Y-330513D01*
X519076Y-330539D01*
X519139Y-330572D01*
X519202Y-330609D01*
X519261Y-330658D01*
X519264Y-330661D01*
X519268Y-330665D01*
X519279Y-330676D01*
X519294Y-330687D01*
X519331Y-330724D01*
X519375Y-330776D01*
X519423Y-330839D01*
X519475Y-330913D01*
X519523Y-330998D01*
X519564Y-331094D01*
Y-331098D01*
X519568Y-331105D01*
X519575Y-331120D01*
X519579Y-331142D01*
X519590Y-331168D01*
X519597Y-331198D01*
X519605Y-331231D01*
X519616Y-331272D01*
X519627Y-331312D01*
X519634Y-331361D01*
X519653Y-331464D01*
X519664Y-331579D01*
X519668Y-331705D01*
Y-331708D01*
Y-331716D01*
Y-331734D01*
Y-331753D01*
X519664Y-331779D01*
Y-331808D01*
X519660Y-331878D01*
X519649Y-331960D01*
X519638Y-332045D01*
X519620Y-332134D01*
X519597Y-332223D01*
Y-332226D01*
X519594Y-332234D01*
X519590Y-332245D01*
X519586Y-332260D01*
X519571Y-332300D01*
X519549Y-332352D01*
X519527Y-332411D01*
X519497Y-332470D01*
X519460Y-332533D01*
X519423Y-332593D01*
X519420Y-332600D01*
X519405Y-332618D01*
X519383Y-332644D01*
X519353Y-332678D01*
X519320Y-332715D01*
X519279Y-332752D01*
X519239Y-332792D01*
X519190Y-332826D01*
X519183Y-332829D01*
X519168Y-332840D01*
X519142Y-332855D01*
X519105Y-332874D01*
X519061Y-332896D01*
X519009Y-332914D01*
X518950Y-332937D01*
X518883Y-332955D01*
X518876D01*
X518865Y-332959D01*
X518854Y-332963D01*
X518817Y-332966D01*
X518765Y-332974D01*
X518706Y-332981D01*
X518635Y-332989D01*
X518558Y-332992D01*
X518473Y-332996D01*
X517551D01*
Y-330435D01*
X518536D01*
X518602Y-330439D01*
D02*
G37*
G36*
X520873Y-346575D02*
X520899D01*
X520929Y-346579D01*
X520999Y-346594D01*
X521077Y-346612D01*
X521158Y-346642D01*
X521240Y-346686D01*
X521281Y-346712D01*
X521318Y-346742D01*
X521321Y-346746D01*
X521325Y-346749D01*
X521336Y-346760D01*
X521347Y-346772D01*
X521366Y-346790D01*
X521381Y-346812D01*
X521421Y-346864D01*
X521462Y-346931D01*
X521499Y-347012D01*
X521532Y-347105D01*
X521554Y-347208D01*
X521240Y-347234D01*
Y-347230D01*
X521236Y-347227D01*
X521232Y-347204D01*
X521221Y-347171D01*
X521207Y-347130D01*
X521192Y-347086D01*
X521170Y-347042D01*
X521144Y-347001D01*
X521118Y-346968D01*
X521110Y-346960D01*
X521096Y-346945D01*
X521070Y-346923D01*
X521033Y-346897D01*
X520985Y-346875D01*
X520933Y-346853D01*
X520870Y-346838D01*
X520803Y-346831D01*
X520777D01*
X520748Y-346834D01*
X520715Y-346842D01*
X520670Y-346853D01*
X520626Y-346868D01*
X520581Y-346886D01*
X520537Y-346916D01*
X520529Y-346919D01*
X520511Y-346934D01*
X520485Y-346960D01*
X520452Y-346997D01*
X520415Y-347042D01*
X520374Y-347093D01*
X520337Y-347160D01*
X520300Y-347234D01*
Y-347238D01*
X520296Y-347245D01*
X520293Y-347256D01*
X520285Y-347271D01*
X520282Y-347293D01*
X520274Y-347319D01*
X520267Y-347349D01*
X520259Y-347386D01*
X520248Y-347426D01*
X520241Y-347471D01*
X520233Y-347519D01*
X520230Y-347571D01*
X520222Y-347630D01*
X520219Y-347689D01*
X520215Y-347756D01*
Y-347822D01*
X520219Y-347819D01*
X520233Y-347796D01*
X520259Y-347767D01*
X520293Y-347730D01*
X520330Y-347685D01*
X520378Y-347645D01*
X520430Y-347604D01*
X520489Y-347567D01*
X520493D01*
X520496Y-347563D01*
X520518Y-347552D01*
X520552Y-347541D01*
X520596Y-347523D01*
X520648Y-347508D01*
X520707Y-347497D01*
X520770Y-347486D01*
X520836Y-347482D01*
X520866D01*
X520888Y-347486D01*
X520918Y-347489D01*
X520948Y-347493D01*
X520985Y-347500D01*
X521022Y-347512D01*
X521107Y-347537D01*
X521151Y-347556D01*
X521195Y-347582D01*
X521240Y-347608D01*
X521288Y-347637D01*
X521332Y-347674D01*
X521373Y-347715D01*
X521377Y-347719D01*
X521384Y-347726D01*
X521395Y-347737D01*
X521406Y-347756D01*
X521425Y-347782D01*
X521443Y-347808D01*
X521462Y-347841D01*
X521484Y-347878D01*
X521506Y-347919D01*
X521525Y-347963D01*
X521543Y-348015D01*
X521562Y-348066D01*
X521573Y-348122D01*
X521584Y-348185D01*
X521591Y-348248D01*
X521595Y-348314D01*
Y-348318D01*
Y-348325D01*
Y-348337D01*
Y-348355D01*
X521591Y-348377D01*
Y-348399D01*
X521580Y-348459D01*
X521569Y-348529D01*
X521551Y-348603D01*
X521525Y-348684D01*
X521488Y-348762D01*
Y-348766D01*
X521484Y-348769D01*
X521477Y-348781D01*
X521469Y-348795D01*
X521447Y-348832D01*
X521414Y-348881D01*
X521373Y-348932D01*
X521325Y-348984D01*
X521266Y-349036D01*
X521203Y-349080D01*
X521199D01*
X521195Y-349084D01*
X521184Y-349091D01*
X521170Y-349095D01*
X521133Y-349114D01*
X521084Y-349132D01*
X521022Y-349154D01*
X520951Y-349169D01*
X520873Y-349184D01*
X520788Y-349188D01*
X520770D01*
X520751Y-349184D01*
X520722D01*
X520689Y-349180D01*
X520652Y-349173D01*
X520607Y-349162D01*
X520563Y-349151D01*
X520511Y-349136D01*
X520459Y-349117D01*
X520407Y-349095D01*
X520352Y-349065D01*
X520300Y-349032D01*
X520248Y-348995D01*
X520196Y-348951D01*
X520148Y-348899D01*
X520145Y-348895D01*
X520137Y-348884D01*
X520126Y-348869D01*
X520111Y-348844D01*
X520089Y-348810D01*
X520071Y-348773D01*
X520048Y-348725D01*
X520026Y-348673D01*
X520000Y-348610D01*
X519978Y-348540D01*
X519960Y-348462D01*
X519941Y-348377D01*
X519923Y-348281D01*
X519911Y-348178D01*
X519904Y-348066D01*
X519901Y-347948D01*
Y-347944D01*
Y-347941D01*
Y-347930D01*
Y-347915D01*
X519904Y-347878D01*
Y-347826D01*
X519908Y-347767D01*
X519915Y-347696D01*
X519923Y-347619D01*
X519934Y-347534D01*
X519948Y-347449D01*
X519967Y-347356D01*
X519989Y-347267D01*
X520015Y-347179D01*
X520048Y-347093D01*
X520085Y-347012D01*
X520126Y-346934D01*
X520174Y-346868D01*
X520178Y-346864D01*
X520185Y-346857D01*
X520200Y-346842D01*
X520219Y-346820D01*
X520241Y-346797D01*
X520270Y-346775D01*
X520307Y-346746D01*
X520344Y-346720D01*
X520389Y-346694D01*
X520437Y-346664D01*
X520493Y-346642D01*
X520548Y-346616D01*
X520611Y-346598D01*
X520678Y-346583D01*
X520748Y-346575D01*
X520822Y-346572D01*
X520851D01*
X520873Y-346575D01*
D02*
G37*
G36*
X518513Y-346586D02*
X518587Y-346590D01*
X518661Y-346598D01*
X518735Y-346609D01*
X518798Y-346620D01*
X518802D01*
X518809Y-346623D01*
X518820D01*
X518835Y-346631D01*
X518876Y-346642D01*
X518927Y-346660D01*
X518987Y-346686D01*
X519049Y-346720D01*
X519112Y-346757D01*
X519172Y-346805D01*
X519175Y-346809D01*
X519179Y-346812D01*
X519190Y-346823D01*
X519205Y-346834D01*
X519242Y-346871D01*
X519286Y-346923D01*
X519334Y-346986D01*
X519386Y-347060D01*
X519434Y-347145D01*
X519475Y-347241D01*
Y-347245D01*
X519479Y-347252D01*
X519486Y-347267D01*
X519490Y-347289D01*
X519501Y-347315D01*
X519508Y-347345D01*
X519516Y-347378D01*
X519527Y-347419D01*
X519538Y-347460D01*
X519545Y-347508D01*
X519564Y-347611D01*
X519575Y-347726D01*
X519579Y-347852D01*
Y-347856D01*
Y-347863D01*
Y-347882D01*
Y-347900D01*
X519575Y-347926D01*
Y-347955D01*
X519571Y-348026D01*
X519560Y-348107D01*
X519549Y-348192D01*
X519530Y-348281D01*
X519508Y-348370D01*
Y-348374D01*
X519505Y-348381D01*
X519501Y-348392D01*
X519497Y-348407D01*
X519482Y-348448D01*
X519460Y-348499D01*
X519438Y-348559D01*
X519408Y-348618D01*
X519371Y-348681D01*
X519334Y-348740D01*
X519331Y-348747D01*
X519316Y-348766D01*
X519294Y-348792D01*
X519264Y-348825D01*
X519231Y-348862D01*
X519190Y-348899D01*
X519149Y-348940D01*
X519101Y-348973D01*
X519094Y-348977D01*
X519079Y-348988D01*
X519053Y-349003D01*
X519016Y-349021D01*
X518972Y-349043D01*
X518920Y-349062D01*
X518861Y-349084D01*
X518794Y-349102D01*
X518787D01*
X518776Y-349106D01*
X518764Y-349110D01*
X518727Y-349114D01*
X518676Y-349121D01*
X518617Y-349128D01*
X518546Y-349136D01*
X518469Y-349139D01*
X518383Y-349143D01*
X517462D01*
Y-346583D01*
X518446D01*
X518513Y-346586D01*
D02*
G37*
G36*
X638305Y-323719D02*
X638301Y-323786D01*
X638297Y-323860D01*
X638290Y-323934D01*
X638279Y-324008D01*
X638268Y-324071D01*
Y-324074D01*
X638264Y-324082D01*
Y-324093D01*
X638257Y-324108D01*
X638245Y-324148D01*
X638227Y-324200D01*
X638201Y-324259D01*
X638168Y-324322D01*
X638131Y-324385D01*
X638083Y-324444D01*
X638079Y-324448D01*
X638075Y-324452D01*
X638064Y-324463D01*
X638053Y-324478D01*
X638016Y-324515D01*
X637964Y-324559D01*
X637901Y-324607D01*
X637827Y-324659D01*
X637742Y-324707D01*
X637646Y-324748D01*
X637642D01*
X637635Y-324751D01*
X637620Y-324759D01*
X637598Y-324763D01*
X637572Y-324774D01*
X637542Y-324781D01*
X637509Y-324788D01*
X637468Y-324799D01*
X637428Y-324811D01*
X637380Y-324818D01*
X637276Y-324836D01*
X637161Y-324848D01*
X637036Y-324851D01*
X637032D01*
X637024D01*
X637006D01*
X636987D01*
X636962Y-324848D01*
X636932D01*
X636862Y-324844D01*
X636780Y-324833D01*
X636695Y-324822D01*
X636606Y-324803D01*
X636518Y-324781D01*
X636514D01*
X636507Y-324777D01*
X636495Y-324774D01*
X636481Y-324770D01*
X636440Y-324755D01*
X636388Y-324733D01*
X636329Y-324711D01*
X636270Y-324681D01*
X636207Y-324644D01*
X636148Y-324607D01*
X636140Y-324603D01*
X636122Y-324589D01*
X636096Y-324566D01*
X636062Y-324537D01*
X636025Y-324503D01*
X635989Y-324463D01*
X635948Y-324422D01*
X635915Y-324374D01*
X635911Y-324367D01*
X635900Y-324352D01*
X635885Y-324326D01*
X635866Y-324289D01*
X635844Y-324244D01*
X635826Y-324193D01*
X635804Y-324133D01*
X635785Y-324067D01*
Y-324060D01*
X635781Y-324048D01*
X635778Y-324037D01*
X635774Y-324000D01*
X635767Y-323949D01*
X635759Y-323889D01*
X635752Y-323819D01*
X635748Y-323741D01*
X635744Y-323656D01*
Y-322735D01*
X638305D01*
Y-323719D01*
D02*
G37*
G36*
X636521Y-325188D02*
X636544D01*
X636569Y-325192D01*
X636629Y-325199D01*
X636695Y-325214D01*
X636762Y-325236D01*
X636832Y-325269D01*
X636899Y-325310D01*
X636902D01*
X636906Y-325318D01*
X636925Y-325332D01*
X636954Y-325362D01*
X636991Y-325403D01*
X637028Y-325454D01*
X637069Y-325517D01*
X637102Y-325588D01*
X637128Y-325673D01*
Y-325669D01*
X637132Y-325665D01*
X637136Y-325654D01*
X637143Y-325639D01*
X637158Y-325606D01*
X637180Y-325562D01*
X637210Y-325514D01*
X637247Y-325465D01*
X637287Y-325421D01*
X637332Y-325380D01*
X637339Y-325377D01*
X637354Y-325366D01*
X637383Y-325351D01*
X637420Y-325336D01*
X637468Y-325318D01*
X637524Y-325303D01*
X637587Y-325292D01*
X637653Y-325288D01*
X637657D01*
X637665D01*
X637679D01*
X637702Y-325292D01*
X637724Y-325295D01*
X637753Y-325299D01*
X637816Y-325314D01*
X637890Y-325336D01*
X637968Y-325373D01*
X638009Y-325395D01*
X638049Y-325421D01*
X638086Y-325454D01*
X638123Y-325488D01*
X638127Y-325491D01*
X638131Y-325499D01*
X638142Y-325510D01*
X638153Y-325525D01*
X638168Y-325543D01*
X638183Y-325569D01*
X638201Y-325599D01*
X638220Y-325628D01*
X638238Y-325665D01*
X638257Y-325706D01*
X638271Y-325750D01*
X638286Y-325799D01*
X638308Y-325902D01*
X638312Y-325961D01*
X638316Y-326021D01*
Y-326054D01*
X638312Y-326076D01*
X638308Y-326106D01*
X638305Y-326139D01*
X638301Y-326176D01*
X638290Y-326213D01*
X638268Y-326302D01*
X638234Y-326391D01*
X638212Y-326435D01*
X638186Y-326479D01*
X638153Y-326520D01*
X638120Y-326561D01*
X638116Y-326564D01*
X638112Y-326568D01*
X638101Y-326579D01*
X638086Y-326594D01*
X638064Y-326609D01*
X638042Y-326627D01*
X637987Y-326664D01*
X637916Y-326701D01*
X637835Y-326735D01*
X637742Y-326761D01*
X637694Y-326764D01*
X637642Y-326768D01*
X637639D01*
X637635D01*
X637613D01*
X637579Y-326764D01*
X637539Y-326757D01*
X637487Y-326746D01*
X637435Y-326727D01*
X637383Y-326705D01*
X637332Y-326672D01*
X637324Y-326668D01*
X637309Y-326653D01*
X637287Y-326631D01*
X637258Y-326601D01*
X637224Y-326561D01*
X637191Y-326513D01*
X637158Y-326457D01*
X637128Y-326391D01*
Y-326394D01*
X637124Y-326402D01*
X637121Y-326413D01*
X637113Y-326428D01*
X637095Y-326472D01*
X637069Y-326524D01*
X637032Y-326579D01*
X636991Y-326638D01*
X636939Y-326694D01*
X636880Y-326746D01*
X636876D01*
X636873Y-326749D01*
X636851Y-326764D01*
X636814Y-326786D01*
X636765Y-326809D01*
X636706Y-326831D01*
X636636Y-326853D01*
X636558Y-326868D01*
X636473Y-326871D01*
X636470D01*
X636458D01*
X636440D01*
X636418Y-326868D01*
X636392Y-326864D01*
X636358Y-326860D01*
X636321Y-326853D01*
X636281Y-326842D01*
X636196Y-326816D01*
X636148Y-326798D01*
X636103Y-326772D01*
X636055Y-326746D01*
X636011Y-326716D01*
X635966Y-326679D01*
X635922Y-326638D01*
X635918Y-326635D01*
X635911Y-326627D01*
X635900Y-326616D01*
X635889Y-326598D01*
X635870Y-326572D01*
X635852Y-326546D01*
X635833Y-326513D01*
X635811Y-326476D01*
X635789Y-326435D01*
X635770Y-326387D01*
X635752Y-326335D01*
X635733Y-326283D01*
X635722Y-326224D01*
X635711Y-326161D01*
X635704Y-326098D01*
X635700Y-326028D01*
Y-325991D01*
X635704Y-325965D01*
X635707Y-325932D01*
X635711Y-325895D01*
X635718Y-325854D01*
X635730Y-325810D01*
X635755Y-325710D01*
X635774Y-325658D01*
X635792Y-325610D01*
X635818Y-325558D01*
X635848Y-325506D01*
X635881Y-325458D01*
X635922Y-325414D01*
X635926Y-325410D01*
X635933Y-325403D01*
X635944Y-325392D01*
X635963Y-325377D01*
X635985Y-325362D01*
X636011Y-325340D01*
X636040Y-325321D01*
X636077Y-325299D01*
X636114Y-325277D01*
X636159Y-325258D01*
X636251Y-325221D01*
X636307Y-325206D01*
X636362Y-325195D01*
X636421Y-325188D01*
X636481Y-325184D01*
X636484D01*
X636492D01*
X636507D01*
X636521Y-325188D01*
D02*
G37*
G36*
X656989Y-323819D02*
X656985Y-323886D01*
X656981Y-323960D01*
X656974Y-324034D01*
X656963Y-324108D01*
X656952Y-324171D01*
Y-324174D01*
X656948Y-324182D01*
Y-324193D01*
X656941Y-324208D01*
X656930Y-324249D01*
X656911Y-324300D01*
X656885Y-324359D01*
X656852Y-324422D01*
X656815Y-324485D01*
X656767Y-324545D01*
X656763Y-324548D01*
X656759Y-324552D01*
X656748Y-324563D01*
X656737Y-324578D01*
X656700Y-324615D01*
X656648Y-324659D01*
X656586Y-324707D01*
X656511Y-324759D01*
X656426Y-324807D01*
X656330Y-324848D01*
X656326D01*
X656319Y-324852D01*
X656304Y-324859D01*
X656282Y-324863D01*
X656256Y-324874D01*
X656227Y-324881D01*
X656193Y-324889D01*
X656153Y-324900D01*
X656112Y-324911D01*
X656064Y-324918D01*
X655960Y-324937D01*
X655845Y-324948D01*
X655720Y-324952D01*
X655716D01*
X655709D01*
X655690D01*
X655672D01*
X655646Y-324948D01*
X655616D01*
X655546Y-324944D01*
X655464Y-324933D01*
X655379Y-324922D01*
X655291Y-324903D01*
X655202Y-324881D01*
X655198D01*
X655191Y-324878D01*
X655180Y-324874D01*
X655165Y-324870D01*
X655124Y-324855D01*
X655072Y-324833D01*
X655013Y-324811D01*
X654954Y-324781D01*
X654891Y-324744D01*
X654832Y-324707D01*
X654824Y-324704D01*
X654806Y-324689D01*
X654780Y-324667D01*
X654747Y-324637D01*
X654710Y-324604D01*
X654673Y-324563D01*
X654632Y-324522D01*
X654599Y-324474D01*
X654595Y-324467D01*
X654584Y-324452D01*
X654569Y-324426D01*
X654551Y-324389D01*
X654528Y-324345D01*
X654510Y-324293D01*
X654488Y-324234D01*
X654469Y-324167D01*
Y-324160D01*
X654465Y-324149D01*
X654462Y-324138D01*
X654458Y-324101D01*
X654451Y-324049D01*
X654443Y-323990D01*
X654436Y-323919D01*
X654432Y-323842D01*
X654428Y-323756D01*
Y-322835D01*
X656989D01*
Y-323819D01*
D02*
G37*
G36*
X656955Y-326968D02*
X656708D01*
X656704Y-326964D01*
X656697Y-326957D01*
X656682Y-326942D01*
X656660Y-326927D01*
X656634Y-326905D01*
X656604Y-326876D01*
X656567Y-326846D01*
X656523Y-326813D01*
X656478Y-326779D01*
X656426Y-326739D01*
X656367Y-326698D01*
X656308Y-326657D01*
X656241Y-326613D01*
X656171Y-326568D01*
X656093Y-326524D01*
X656016Y-326480D01*
X656012Y-326476D01*
X655997Y-326469D01*
X655975Y-326458D01*
X655942Y-326439D01*
X655901Y-326420D01*
X655857Y-326398D01*
X655805Y-326372D01*
X655746Y-326346D01*
X655679Y-326317D01*
X655612Y-326284D01*
X655538Y-326254D01*
X655461Y-326224D01*
X655302Y-326165D01*
X655131Y-326110D01*
X655128D01*
X655117Y-326106D01*
X655098Y-326102D01*
X655076Y-326095D01*
X655046Y-326087D01*
X655009Y-326080D01*
X654969Y-326069D01*
X654924Y-326062D01*
X654872Y-326050D01*
X654817Y-326039D01*
X654699Y-326021D01*
X654569Y-326002D01*
X654428Y-325991D01*
Y-325669D01*
X654432D01*
X654443D01*
X654458D01*
X654480Y-325673D01*
X654510D01*
X654547Y-325677D01*
X654588Y-325680D01*
X654632Y-325684D01*
X654684Y-325692D01*
X654736Y-325699D01*
X654798Y-325710D01*
X654861Y-325721D01*
X654928Y-325732D01*
X655002Y-325747D01*
X655154Y-325784D01*
X655157D01*
X655172Y-325788D01*
X655194Y-325795D01*
X655228Y-325806D01*
X655265Y-325817D01*
X655309Y-325832D01*
X655361Y-325847D01*
X655416Y-325869D01*
X655479Y-325891D01*
X655542Y-325914D01*
X655683Y-325969D01*
X655831Y-326036D01*
X655979Y-326110D01*
X655982Y-326113D01*
X655997Y-326121D01*
X656016Y-326132D01*
X656045Y-326147D01*
X656079Y-326165D01*
X656119Y-326191D01*
X656164Y-326217D01*
X656212Y-326247D01*
X656319Y-326317D01*
X656430Y-326391D01*
X656545Y-326476D01*
X656652Y-326565D01*
Y-325310D01*
X656955D01*
Y-326968D01*
D02*
G37*
G36*
X578839Y-119312D02*
X576838D01*
X576841Y-119316D01*
X576856Y-119334D01*
X576878Y-119357D01*
X576904Y-119394D01*
X576937Y-119434D01*
X576974Y-119486D01*
X577015Y-119545D01*
X577056Y-119612D01*
Y-119615D01*
X577060Y-119619D01*
X577074Y-119641D01*
X577093Y-119678D01*
X577115Y-119723D01*
X577141Y-119775D01*
X577167Y-119830D01*
X577193Y-119886D01*
X577215Y-119941D01*
X576912D01*
Y-119937D01*
X576904Y-119930D01*
X576900Y-119915D01*
X576889Y-119897D01*
X576878Y-119875D01*
X576863Y-119849D01*
X576826Y-119786D01*
X576786Y-119712D01*
X576734Y-119638D01*
X576675Y-119560D01*
X576612Y-119482D01*
X576608Y-119479D01*
X576605Y-119475D01*
X576593Y-119464D01*
X576582Y-119449D01*
X576545Y-119416D01*
X576501Y-119371D01*
X576449Y-119327D01*
X576390Y-119279D01*
X576331Y-119238D01*
X576268Y-119201D01*
Y-118998D01*
X578839D01*
Y-119312D01*
D02*
G37*
G36*
X578048Y-120474D02*
X578070Y-120481D01*
X578099Y-120492D01*
X578133Y-120503D01*
X578173Y-120518D01*
X578218Y-120537D01*
X578266Y-120559D01*
X578369Y-120611D01*
X578473Y-120677D01*
X578525Y-120718D01*
X578577Y-120759D01*
X578621Y-120803D01*
X578665Y-120855D01*
X578669Y-120859D01*
X578677Y-120866D01*
X578684Y-120885D01*
X578699Y-120903D01*
X578717Y-120933D01*
X578736Y-120962D01*
X578754Y-121003D01*
X578773Y-121044D01*
X578795Y-121092D01*
X578813Y-121144D01*
X578832Y-121199D01*
X578850Y-121258D01*
X578865Y-121321D01*
X578873Y-121388D01*
X578880Y-121458D01*
X578884Y-121532D01*
Y-121573D01*
X578880Y-121602D01*
Y-121636D01*
X578876Y-121676D01*
X578869Y-121721D01*
X578862Y-121773D01*
X578843Y-121880D01*
X578813Y-121991D01*
X578773Y-122102D01*
X578747Y-122154D01*
X578717Y-122205D01*
X578714Y-122209D01*
X578710Y-122217D01*
X578699Y-122231D01*
X578684Y-122246D01*
X578669Y-122268D01*
X578647Y-122294D01*
X578621Y-122324D01*
X578591Y-122353D01*
X578558Y-122383D01*
X578525Y-122416D01*
X578440Y-122483D01*
X578340Y-122546D01*
X578229Y-122601D01*
X578225D01*
X578214Y-122609D01*
X578195Y-122613D01*
X578173Y-122624D01*
X578144Y-122631D01*
X578107Y-122642D01*
X578066Y-122657D01*
X578022Y-122668D01*
X577974Y-122679D01*
X577918Y-122694D01*
X577803Y-122712D01*
X577674Y-122727D01*
X577541Y-122735D01*
X577537D01*
X577522D01*
X577500D01*
X577474Y-122731D01*
X577437D01*
X577400Y-122727D01*
X577352Y-122723D01*
X577304Y-122716D01*
X577197Y-122698D01*
X577078Y-122672D01*
X576960Y-122635D01*
X576845Y-122583D01*
X576841Y-122579D01*
X576830Y-122575D01*
X576815Y-122568D01*
X576797Y-122553D01*
X576771Y-122538D01*
X576741Y-122520D01*
X576675Y-122472D01*
X576601Y-122409D01*
X576527Y-122335D01*
X576453Y-122250D01*
X576390Y-122150D01*
X576386Y-122146D01*
X576382Y-122135D01*
X576375Y-122120D01*
X576364Y-122102D01*
X576353Y-122072D01*
X576342Y-122043D01*
X576327Y-122006D01*
X576312Y-121965D01*
X576297Y-121921D01*
X576283Y-121872D01*
X576260Y-121769D01*
X576242Y-121651D01*
X576234Y-121528D01*
Y-121491D01*
X576238Y-121466D01*
X576242Y-121432D01*
X576246Y-121391D01*
X576249Y-121351D01*
X576260Y-121303D01*
X576283Y-121203D01*
X576316Y-121092D01*
X576338Y-121036D01*
X576364Y-120984D01*
X576397Y-120933D01*
X576431Y-120881D01*
X576434Y-120877D01*
X576438Y-120870D01*
X576449Y-120855D01*
X576468Y-120836D01*
X576486Y-120818D01*
X576512Y-120792D01*
X576542Y-120766D01*
X576571Y-120737D01*
X576608Y-120707D01*
X576653Y-120677D01*
X576697Y-120644D01*
X576745Y-120615D01*
X576801Y-120589D01*
X576856Y-120559D01*
X576915Y-120537D01*
X576982Y-120515D01*
X577060Y-120848D01*
X577056D01*
X577048Y-120851D01*
X577034Y-120859D01*
X577015Y-120866D01*
X576993Y-120873D01*
X576963Y-120885D01*
X576904Y-120914D01*
X576838Y-120951D01*
X576771Y-120996D01*
X576708Y-121051D01*
X576653Y-121110D01*
X576645Y-121118D01*
X576630Y-121140D01*
X576612Y-121177D01*
X576586Y-121225D01*
X576564Y-121288D01*
X576542Y-121358D01*
X576527Y-121443D01*
X576523Y-121536D01*
Y-121565D01*
X576527Y-121584D01*
Y-121610D01*
X576531Y-121639D01*
X576542Y-121710D01*
X576556Y-121787D01*
X576582Y-121869D01*
X576619Y-121954D01*
X576667Y-122032D01*
Y-122035D01*
X576675Y-122039D01*
X576693Y-122065D01*
X576723Y-122098D01*
X576767Y-122139D01*
X576823Y-122187D01*
X576886Y-122231D01*
X576963Y-122272D01*
X577048Y-122309D01*
X577052D01*
X577060Y-122313D01*
X577071Y-122317D01*
X577089Y-122320D01*
X577111Y-122328D01*
X577137Y-122335D01*
X577200Y-122346D01*
X577274Y-122361D01*
X577356Y-122376D01*
X577444Y-122383D01*
X577541Y-122387D01*
X577544D01*
X577555D01*
X577574D01*
X577596D01*
X577622Y-122383D01*
X577655D01*
X577692Y-122379D01*
X577733Y-122376D01*
X577822Y-122365D01*
X577918Y-122346D01*
X578014Y-122324D01*
X578110Y-122294D01*
X578114D01*
X578122Y-122291D01*
X578133Y-122283D01*
X578151Y-122276D01*
X578195Y-122254D01*
X578247Y-122220D01*
X578306Y-122180D01*
X578369Y-122128D01*
X578425Y-122069D01*
X578477Y-121998D01*
Y-121995D01*
X578480Y-121987D01*
X578488Y-121976D01*
X578495Y-121961D01*
X578503Y-121943D01*
X578514Y-121921D01*
X578536Y-121869D01*
X578558Y-121802D01*
X578577Y-121728D01*
X578591Y-121647D01*
X578595Y-121562D01*
Y-121536D01*
X578591Y-121514D01*
Y-121488D01*
X578588Y-121462D01*
X578573Y-121395D01*
X578554Y-121318D01*
X578525Y-121240D01*
X578484Y-121158D01*
X578462Y-121118D01*
X578432Y-121081D01*
X578429Y-121077D01*
X578425Y-121073D01*
X578414Y-121062D01*
X578403Y-121047D01*
X578384Y-121033D01*
X578362Y-121014D01*
X578340Y-120992D01*
X578310Y-120973D01*
X578277Y-120951D01*
X578240Y-120925D01*
X578203Y-120903D01*
X578159Y-120881D01*
X578110Y-120862D01*
X578059Y-120844D01*
X578003Y-120825D01*
X577944Y-120811D01*
X578029Y-120470D01*
X578033D01*
X578048Y-120474D01*
D02*
G37*
G36*
X147695Y-348389D02*
X148043D01*
Y-348678D01*
X147695D01*
Y-349292D01*
X147381D01*
Y-348678D01*
X146267D01*
Y-348389D01*
X147440Y-346732D01*
X147695D01*
Y-348389D01*
D02*
G37*
G36*
X145294Y-346724D02*
X145323Y-346728D01*
X145360Y-346732D01*
X145401Y-346739D01*
X145442Y-346746D01*
X145538Y-346772D01*
X145634Y-346809D01*
X145682Y-346831D01*
X145730Y-346857D01*
X145775Y-346891D01*
X145816Y-346928D01*
X145819Y-346931D01*
X145827Y-346935D01*
X145834Y-346950D01*
X145849Y-346965D01*
X145867Y-346983D01*
X145886Y-347009D01*
X145904Y-347035D01*
X145926Y-347068D01*
X145964Y-347139D01*
X146001Y-347227D01*
X146015Y-347272D01*
X146023Y-347324D01*
X146030Y-347375D01*
X146034Y-347431D01*
Y-347438D01*
Y-347457D01*
X146030Y-347486D01*
X146026Y-347527D01*
X146019Y-347571D01*
X146004Y-347623D01*
X145989Y-347679D01*
X145967Y-347734D01*
X145964Y-347742D01*
X145956Y-347760D01*
X145941Y-347790D01*
X145919Y-347831D01*
X145889Y-347875D01*
X145852Y-347930D01*
X145808Y-347986D01*
X145756Y-348049D01*
X145749Y-348056D01*
X145730Y-348078D01*
X145712Y-348097D01*
X145693Y-348115D01*
X145671Y-348138D01*
X145642Y-348167D01*
X145612Y-348197D01*
X145575Y-348230D01*
X145538Y-348267D01*
X145494Y-348308D01*
X145446Y-348348D01*
X145394Y-348397D01*
X145334Y-348445D01*
X145275Y-348497D01*
X145272Y-348500D01*
X145264Y-348508D01*
X145249Y-348519D01*
X145231Y-348534D01*
X145209Y-348556D01*
X145183Y-348578D01*
X145124Y-348626D01*
X145061Y-348681D01*
X145001Y-348737D01*
X144950Y-348785D01*
X144928Y-348804D01*
X144909Y-348822D01*
X144905Y-348826D01*
X144894Y-348837D01*
X144879Y-348852D01*
X144861Y-348874D01*
X144842Y-348900D01*
X144820Y-348926D01*
X144776Y-348989D01*
X146037D01*
Y-349292D01*
X144339D01*
Y-349288D01*
Y-349273D01*
Y-349251D01*
X144343Y-349222D01*
X144347Y-349188D01*
X144354Y-349151D01*
X144361Y-349114D01*
X144376Y-349074D01*
Y-349070D01*
X144380Y-349066D01*
X144387Y-349044D01*
X144402Y-349011D01*
X144424Y-348966D01*
X144454Y-348915D01*
X144491Y-348855D01*
X144532Y-348796D01*
X144583Y-348733D01*
Y-348730D01*
X144591Y-348726D01*
X144609Y-348704D01*
X144643Y-348670D01*
X144691Y-348622D01*
X144746Y-348567D01*
X144817Y-348500D01*
X144902Y-348426D01*
X144994Y-348348D01*
X144998Y-348345D01*
X145013Y-348334D01*
X145035Y-348315D01*
X145061Y-348293D01*
X145094Y-348263D01*
X145135Y-348230D01*
X145175Y-348193D01*
X145223Y-348152D01*
X145316Y-348064D01*
X145408Y-347975D01*
X145453Y-347930D01*
X145494Y-347886D01*
X145531Y-347845D01*
X145560Y-347805D01*
Y-347801D01*
X145568Y-347797D01*
X145575Y-347786D01*
X145582Y-347771D01*
X145608Y-347731D01*
X145638Y-347682D01*
X145664Y-347623D01*
X145690Y-347560D01*
X145704Y-347490D01*
X145712Y-347424D01*
Y-347420D01*
Y-347416D01*
X145708Y-347394D01*
X145704Y-347357D01*
X145693Y-347316D01*
X145679Y-347264D01*
X145653Y-347213D01*
X145619Y-347161D01*
X145575Y-347109D01*
X145568Y-347102D01*
X145549Y-347087D01*
X145523Y-347068D01*
X145483Y-347042D01*
X145431Y-347020D01*
X145371Y-346998D01*
X145301Y-346983D01*
X145223Y-346979D01*
X145201D01*
X145186Y-346983D01*
X145142Y-346987D01*
X145090Y-346998D01*
X145035Y-347013D01*
X144972Y-347039D01*
X144913Y-347072D01*
X144857Y-347116D01*
X144850Y-347124D01*
X144835Y-347142D01*
X144813Y-347172D01*
X144791Y-347216D01*
X144765Y-347268D01*
X144743Y-347335D01*
X144728Y-347409D01*
X144720Y-347494D01*
X144398Y-347461D01*
Y-347457D01*
X144402Y-347446D01*
Y-347427D01*
X144406Y-347401D01*
X144413Y-347372D01*
X144421Y-347338D01*
X144432Y-347298D01*
X144443Y-347257D01*
X144472Y-347168D01*
X144517Y-347079D01*
X144543Y-347035D01*
X144576Y-346991D01*
X144609Y-346950D01*
X144646Y-346913D01*
X144650Y-346909D01*
X144657Y-346905D01*
X144668Y-346894D01*
X144687Y-346883D01*
X144709Y-346868D01*
X144735Y-346854D01*
X144765Y-346835D01*
X144802Y-346817D01*
X144842Y-346798D01*
X144887Y-346780D01*
X144935Y-346765D01*
X144987Y-346750D01*
X145042Y-346739D01*
X145101Y-346728D01*
X145164Y-346724D01*
X145231Y-346721D01*
X145268D01*
X145294Y-346724D01*
D02*
G37*
G36*
X143151Y-346735D02*
X143185D01*
X143263Y-346739D01*
X143344Y-346750D01*
X143433Y-346761D01*
X143514Y-346780D01*
X143555Y-346791D01*
X143588Y-346802D01*
X143592D01*
X143596Y-346806D01*
X143618Y-346817D01*
X143651Y-346831D01*
X143692Y-346857D01*
X143736Y-346891D01*
X143784Y-346935D01*
X143829Y-346987D01*
X143873Y-347046D01*
Y-347050D01*
X143877Y-347054D01*
X143892Y-347076D01*
X143906Y-347113D01*
X143929Y-347161D01*
X143947Y-347216D01*
X143965Y-347283D01*
X143977Y-347353D01*
X143980Y-347431D01*
Y-347435D01*
Y-347442D01*
Y-347457D01*
X143977Y-347475D01*
Y-347501D01*
X143973Y-347527D01*
X143958Y-347590D01*
X143936Y-347664D01*
X143906Y-347742D01*
X143862Y-347819D01*
X143832Y-347856D01*
X143803Y-347893D01*
X143799Y-347897D01*
X143795Y-347901D01*
X143784Y-347912D01*
X143769Y-347923D01*
X143751Y-347938D01*
X143729Y-347953D01*
X143699Y-347971D01*
X143669Y-347993D01*
X143632Y-348012D01*
X143592Y-348030D01*
X143547Y-348053D01*
X143499Y-348071D01*
X143444Y-348086D01*
X143388Y-348104D01*
X143325Y-348115D01*
X143259Y-348127D01*
X143266Y-348130D01*
X143281Y-348138D01*
X143303Y-348152D01*
X143333Y-348167D01*
X143399Y-348208D01*
X143433Y-348234D01*
X143462Y-348256D01*
X143470Y-348263D01*
X143488Y-348282D01*
X143518Y-348311D01*
X143555Y-348348D01*
X143596Y-348400D01*
X143644Y-348456D01*
X143692Y-348522D01*
X143744Y-348596D01*
X144184Y-349292D01*
X143762D01*
X143425Y-348759D01*
Y-348756D01*
X143418Y-348748D01*
X143411Y-348737D01*
X143399Y-348722D01*
X143374Y-348681D01*
X143340Y-348630D01*
X143299Y-348574D01*
X143259Y-348515D01*
X143218Y-348460D01*
X143181Y-348408D01*
X143177Y-348404D01*
X143166Y-348389D01*
X143148Y-348367D01*
X143122Y-348341D01*
X143066Y-348286D01*
X143037Y-348260D01*
X143007Y-348237D01*
X143003Y-348234D01*
X142996Y-348230D01*
X142981Y-348223D01*
X142959Y-348212D01*
X142937Y-348200D01*
X142911Y-348189D01*
X142852Y-348171D01*
X142848D01*
X142841Y-348167D01*
X142826D01*
X142807Y-348164D01*
X142781Y-348160D01*
X142752D01*
X142711Y-348156D01*
X142275D01*
Y-349292D01*
X141934D01*
Y-346732D01*
X143122D01*
X143151Y-346735D01*
D02*
G37*
G36*
X596495Y-160723D02*
X594764D01*
Y-160420D01*
X596155D01*
Y-159628D01*
X594952D01*
Y-159325D01*
X596155D01*
Y-158163D01*
X596495D01*
Y-160723D01*
D02*
G37*
G36*
X593583Y-160165D02*
X593587Y-160161D01*
X593605Y-160146D01*
X593628Y-160124D01*
X593665Y-160098D01*
X593705Y-160065D01*
X593757Y-160028D01*
X593816Y-159987D01*
X593883Y-159947D01*
X593887D01*
X593890Y-159943D01*
X593913Y-159928D01*
X593950Y-159909D01*
X593994Y-159887D01*
X594046Y-159861D01*
X594101Y-159836D01*
X594157Y-159810D01*
X594212Y-159787D01*
Y-160091D01*
X594208D01*
X594201Y-160098D01*
X594186Y-160102D01*
X594168Y-160113D01*
X594146Y-160124D01*
X594120Y-160139D01*
X594057Y-160176D01*
X593983Y-160217D01*
X593909Y-160268D01*
X593831Y-160328D01*
X593753Y-160390D01*
X593750Y-160394D01*
X593746Y-160398D01*
X593735Y-160409D01*
X593720Y-160420D01*
X593687Y-160457D01*
X593642Y-160502D01*
X593598Y-160553D01*
X593550Y-160612D01*
X593509Y-160672D01*
X593472Y-160735D01*
X593269D01*
Y-158163D01*
X593583D01*
Y-160165D01*
D02*
G37*
G36*
X272253Y-365689D02*
X272335Y-365704D01*
X272405Y-365726D01*
X272464Y-365748D01*
X272512Y-365770D01*
X272549Y-365793D01*
X272571Y-365807D01*
X272579Y-365811D01*
X272634Y-365863D01*
X272682Y-365918D01*
X272720Y-365978D01*
X272749Y-366037D01*
X272771Y-366089D01*
X272786Y-366129D01*
X272790Y-366144D01*
X272793Y-366155D01*
X272797Y-366163D01*
Y-366166D01*
X272831Y-366103D01*
X272864Y-366052D01*
X272901Y-366007D01*
X272934Y-365970D01*
X272964Y-365941D01*
X272990Y-365918D01*
X273004Y-365907D01*
X273012Y-365904D01*
X273063Y-365874D01*
X273115Y-365852D01*
X273167Y-365833D01*
X273215Y-365822D01*
X273256Y-365815D01*
X273286Y-365811D01*
X273308D01*
X273315D01*
X273378Y-365815D01*
X273441Y-365826D01*
X273497Y-365841D01*
X273545Y-365859D01*
X273585Y-365878D01*
X273619Y-365893D01*
X273637Y-365904D01*
X273644Y-365907D01*
X273700Y-365944D01*
X273748Y-365989D01*
X273789Y-366033D01*
X273826Y-366077D01*
X273852Y-366114D01*
X273874Y-366148D01*
X273885Y-366170D01*
X273889Y-366174D01*
Y-366177D01*
X273918Y-366244D01*
X273940Y-366311D01*
X273959Y-366377D01*
X273970Y-366436D01*
X273977Y-366484D01*
X273981Y-366525D01*
Y-366618D01*
X273974Y-366670D01*
X273955Y-366769D01*
X273926Y-366855D01*
X273896Y-366929D01*
X273878Y-366962D01*
X273863Y-366988D01*
X273848Y-367014D01*
X273833Y-367032D01*
X273822Y-367047D01*
X273815Y-367058D01*
X273811Y-367065D01*
X273807Y-367069D01*
X273737Y-367139D01*
X273659Y-367195D01*
X273578Y-367239D01*
X273497Y-367276D01*
X273426Y-367299D01*
X273396Y-367310D01*
X273371Y-367317D01*
X273348Y-367321D01*
X273334Y-367324D01*
X273323Y-367328D01*
X273319D01*
X273263Y-367014D01*
X273345Y-366999D01*
X273415Y-366977D01*
X273474Y-366951D01*
X273522Y-366925D01*
X273559Y-366899D01*
X273585Y-366877D01*
X273604Y-366862D01*
X273607Y-366858D01*
X273644Y-366810D01*
X273674Y-366758D01*
X273692Y-366710D01*
X273707Y-366662D01*
X273715Y-366618D01*
X273722Y-366584D01*
Y-366555D01*
X273718Y-366488D01*
X273704Y-366429D01*
X273685Y-366377D01*
X273667Y-366333D01*
X273644Y-366300D01*
X273626Y-366274D01*
X273611Y-366255D01*
X273607Y-366251D01*
X273563Y-366211D01*
X273515Y-366181D01*
X273467Y-366163D01*
X273422Y-366148D01*
X273382Y-366140D01*
X273352Y-366133D01*
X273330D01*
X273326D01*
X273323D01*
X273282D01*
X273245Y-366140D01*
X273182Y-366159D01*
X273127Y-366185D01*
X273078Y-366214D01*
X273045Y-366244D01*
X273019Y-366270D01*
X273004Y-366288D01*
X273001Y-366292D01*
Y-366296D01*
X272967Y-366359D01*
X272941Y-366418D01*
X272923Y-366481D01*
X272912Y-366536D01*
X272904Y-366584D01*
X272897Y-366625D01*
Y-366673D01*
X272901Y-366688D01*
Y-366706D01*
X272623Y-366743D01*
X272634Y-366695D01*
X272642Y-366651D01*
X272649Y-366614D01*
X272653Y-366581D01*
X272657Y-366555D01*
Y-366522D01*
X272649Y-366444D01*
X272634Y-366373D01*
X272612Y-366311D01*
X272586Y-366259D01*
X272560Y-366218D01*
X272538Y-366189D01*
X272523Y-366170D01*
X272516Y-366163D01*
X272460Y-366114D01*
X272401Y-366077D01*
X272342Y-366052D01*
X272283Y-366037D01*
X272235Y-366026D01*
X272194Y-366022D01*
X272179Y-366018D01*
X272168D01*
X272161D01*
X272157D01*
X272076Y-366026D01*
X272002Y-366044D01*
X271939Y-366066D01*
X271883Y-366096D01*
X271839Y-366126D01*
X271806Y-366148D01*
X271783Y-366166D01*
X271776Y-366174D01*
X271724Y-366233D01*
X271687Y-366296D01*
X271661Y-366359D01*
X271643Y-366418D01*
X271632Y-366470D01*
X271628Y-366510D01*
X271624Y-366525D01*
Y-366547D01*
X271628Y-366614D01*
X271643Y-366677D01*
X271661Y-366732D01*
X271683Y-366777D01*
X271702Y-366814D01*
X271720Y-366843D01*
X271735Y-366858D01*
X271739Y-366866D01*
X271791Y-366910D01*
X271850Y-366947D01*
X271913Y-366980D01*
X271979Y-367006D01*
X272035Y-367025D01*
X272061Y-367032D01*
X272083Y-367036D01*
X272101Y-367039D01*
X272116Y-367043D01*
X272124Y-367047D01*
X272127D01*
X272087Y-367361D01*
X272028Y-367354D01*
X271972Y-367343D01*
X271868Y-367310D01*
X271780Y-367269D01*
X271743Y-367247D01*
X271706Y-367225D01*
X271672Y-367202D01*
X271646Y-367180D01*
X271621Y-367162D01*
X271602Y-367143D01*
X271587Y-367132D01*
X271576Y-367121D01*
X271569Y-367113D01*
X271565Y-367110D01*
X271532Y-367065D01*
X271498Y-367021D01*
X271473Y-366977D01*
X271450Y-366929D01*
X271413Y-366836D01*
X271391Y-366747D01*
X271384Y-366706D01*
X271376Y-366670D01*
X271373Y-366636D01*
X271369Y-366607D01*
X271365Y-366584D01*
Y-366551D01*
X271369Y-366481D01*
X271376Y-366418D01*
X271387Y-366355D01*
X271402Y-366296D01*
X271421Y-366240D01*
X271439Y-366192D01*
X271462Y-366144D01*
X271484Y-366103D01*
X271502Y-366063D01*
X271524Y-366029D01*
X271543Y-366000D01*
X271561Y-365978D01*
X271576Y-365959D01*
X271587Y-365944D01*
X271595Y-365937D01*
X271598Y-365933D01*
X271643Y-365889D01*
X271691Y-365852D01*
X271739Y-365819D01*
X271787Y-365789D01*
X271831Y-365767D01*
X271880Y-365744D01*
X271968Y-365715D01*
X272009Y-365707D01*
X272046Y-365700D01*
X272079Y-365693D01*
X272109Y-365689D01*
X272131Y-365685D01*
X272150D01*
X272161D01*
X272164D01*
X272253Y-365689D01*
D02*
G37*
G36*
X272342Y-367661D02*
X272405Y-367669D01*
X272468Y-367680D01*
X272523Y-367694D01*
X272575Y-367713D01*
X272627Y-367731D01*
X272671Y-367754D01*
X272712Y-367772D01*
X272749Y-367794D01*
X272782Y-367816D01*
X272808Y-367835D01*
X272834Y-367853D01*
X272853Y-367868D01*
X272864Y-367879D01*
X272871Y-367887D01*
X272875Y-367891D01*
X272916Y-367935D01*
X272953Y-367979D01*
X272982Y-368027D01*
X273008Y-368075D01*
X273034Y-368124D01*
X273052Y-368172D01*
X273078Y-368261D01*
X273089Y-368301D01*
X273097Y-368338D01*
X273101Y-368372D01*
X273104Y-368401D01*
X273108Y-368423D01*
Y-368505D01*
X273101Y-368549D01*
X273082Y-368638D01*
X273056Y-368719D01*
X273026Y-368793D01*
X272997Y-368852D01*
X272982Y-368878D01*
X272971Y-368901D01*
X272960Y-368919D01*
X272953Y-368930D01*
X272949Y-368938D01*
X272945Y-368941D01*
X273637Y-368804D01*
Y-367779D01*
X273937D01*
Y-369052D01*
X272620Y-369300D01*
X272579Y-369004D01*
X272620Y-368978D01*
X272653Y-368945D01*
X272686Y-368915D01*
X272712Y-368886D01*
X272730Y-368856D01*
X272749Y-368834D01*
X272756Y-368819D01*
X272760Y-368815D01*
X272782Y-368767D01*
X272801Y-368719D01*
X272812Y-368675D01*
X272823Y-368631D01*
X272827Y-368594D01*
X272831Y-368564D01*
Y-368494D01*
X272823Y-368449D01*
X272805Y-368372D01*
X272779Y-368305D01*
X272753Y-368246D01*
X272723Y-368201D01*
X272697Y-368168D01*
X272679Y-368149D01*
X272675Y-368142D01*
X272671D01*
X272608Y-368090D01*
X272542Y-368053D01*
X272471Y-368027D01*
X272401Y-368009D01*
X272342Y-367998D01*
X272316Y-367994D01*
X272294D01*
X272275Y-367990D01*
X272261D01*
X272253D01*
X272250D01*
X272198D01*
X272150Y-367998D01*
X272057Y-368016D01*
X271979Y-368042D01*
X271917Y-368068D01*
X271865Y-368098D01*
X271824Y-368124D01*
X271813Y-368135D01*
X271802Y-368142D01*
X271798Y-368146D01*
X271795Y-368149D01*
X271765Y-368179D01*
X271739Y-368209D01*
X271694Y-368275D01*
X271665Y-368338D01*
X271646Y-368401D01*
X271632Y-368453D01*
X271628Y-368497D01*
X271624Y-368512D01*
Y-368534D01*
X271628Y-368605D01*
X271643Y-368668D01*
X271661Y-368723D01*
X271683Y-368767D01*
X271706Y-368808D01*
X271724Y-368838D01*
X271739Y-368852D01*
X271743Y-368860D01*
X271795Y-368904D01*
X271850Y-368941D01*
X271913Y-368971D01*
X271968Y-368993D01*
X272024Y-369008D01*
X272065Y-369019D01*
X272083Y-369023D01*
X272094Y-369026D01*
X272101D01*
X272105D01*
X272079Y-369356D01*
X272020Y-369348D01*
X271965Y-369337D01*
X271861Y-369304D01*
X271772Y-369263D01*
X271732Y-369241D01*
X271698Y-369219D01*
X271665Y-369200D01*
X271635Y-369178D01*
X271613Y-369160D01*
X271595Y-369141D01*
X271580Y-369126D01*
X271565Y-369119D01*
X271561Y-369111D01*
X271558Y-369108D01*
X271524Y-369063D01*
X271495Y-369019D01*
X271469Y-368971D01*
X271447Y-368923D01*
X271413Y-368830D01*
X271391Y-368738D01*
X271380Y-368697D01*
X271376Y-368656D01*
X271373Y-368623D01*
X271369Y-368594D01*
X271365Y-368568D01*
Y-368534D01*
X271369Y-368457D01*
X271380Y-368383D01*
X271395Y-368312D01*
X271413Y-368249D01*
X271439Y-368190D01*
X271465Y-368135D01*
X271491Y-368083D01*
X271521Y-368039D01*
X271550Y-367998D01*
X271576Y-367961D01*
X271606Y-367931D01*
X271628Y-367905D01*
X271646Y-367887D01*
X271661Y-367872D01*
X271672Y-367865D01*
X271676Y-367861D01*
X271724Y-367824D01*
X271776Y-367794D01*
X271824Y-367765D01*
X271876Y-367742D01*
X271976Y-367705D01*
X272072Y-367683D01*
X272113Y-367676D01*
X272153Y-367669D01*
X272187Y-367665D01*
X272216Y-367661D01*
X272242Y-367657D01*
X272261D01*
X272272D01*
X272275D01*
X272342Y-367661D01*
D02*
G37*
G36*
X272305Y-369985D02*
X272246Y-370000D01*
X272190Y-370018D01*
X272139Y-370037D01*
X272091Y-370055D01*
X272046Y-370077D01*
X272009Y-370099D01*
X271972Y-370125D01*
X271939Y-370147D01*
X271909Y-370166D01*
X271887Y-370188D01*
X271865Y-370207D01*
X271846Y-370221D01*
X271835Y-370236D01*
X271824Y-370247D01*
X271820Y-370251D01*
X271817Y-370255D01*
X271787Y-370292D01*
X271765Y-370333D01*
X271724Y-370414D01*
X271694Y-370492D01*
X271676Y-370569D01*
X271661Y-370636D01*
X271657Y-370662D01*
Y-370688D01*
X271654Y-370710D01*
Y-370736D01*
X271657Y-370821D01*
X271672Y-370902D01*
X271691Y-370976D01*
X271713Y-371043D01*
X271735Y-371095D01*
X271746Y-371117D01*
X271754Y-371135D01*
X271761Y-371150D01*
X271769Y-371161D01*
X271772Y-371169D01*
Y-371172D01*
X271824Y-371243D01*
X271880Y-371302D01*
X271942Y-371354D01*
X272002Y-371394D01*
X272054Y-371428D01*
X272098Y-371450D01*
X272116Y-371457D01*
X272127Y-371465D01*
X272135Y-371468D01*
X272139D01*
X272235Y-371498D01*
X272331Y-371520D01*
X272427Y-371539D01*
X272516Y-371550D01*
X272557Y-371553D01*
X272594Y-371557D01*
X272627D01*
X272653Y-371561D01*
X272675D01*
X272694D01*
X272705D01*
X272708D01*
X272805Y-371557D01*
X272893Y-371550D01*
X272975Y-371535D01*
X273049Y-371520D01*
X273112Y-371509D01*
X273138Y-371502D01*
X273160Y-371494D01*
X273178Y-371491D01*
X273189Y-371487D01*
X273197Y-371483D01*
X273200D01*
X273286Y-371446D01*
X273363Y-371406D01*
X273426Y-371361D01*
X273482Y-371313D01*
X273526Y-371272D01*
X273556Y-371239D01*
X273574Y-371213D01*
X273582Y-371209D01*
Y-371206D01*
X273630Y-371128D01*
X273667Y-371043D01*
X273692Y-370961D01*
X273707Y-370884D01*
X273718Y-370813D01*
X273722Y-370784D01*
Y-370758D01*
X273726Y-370740D01*
Y-370710D01*
X273722Y-370617D01*
X273707Y-370532D01*
X273685Y-370462D01*
X273663Y-370399D01*
X273637Y-370351D01*
X273619Y-370314D01*
X273604Y-370292D01*
X273596Y-370284D01*
X273541Y-370225D01*
X273478Y-370170D01*
X273411Y-370125D01*
X273345Y-370088D01*
X273286Y-370059D01*
X273256Y-370048D01*
X273234Y-370040D01*
X273215Y-370033D01*
X273200Y-370025D01*
X273193Y-370022D01*
X273189D01*
X273267Y-369689D01*
X273334Y-369711D01*
X273393Y-369733D01*
X273448Y-369763D01*
X273504Y-369789D01*
X273552Y-369818D01*
X273596Y-369851D01*
X273641Y-369881D01*
X273678Y-369911D01*
X273707Y-369940D01*
X273737Y-369966D01*
X273763Y-369992D01*
X273781Y-370011D01*
X273800Y-370029D01*
X273811Y-370044D01*
X273815Y-370051D01*
X273818Y-370055D01*
X273852Y-370107D01*
X273885Y-370159D01*
X273911Y-370210D01*
X273933Y-370266D01*
X273966Y-370377D01*
X273989Y-370477D01*
X274000Y-370525D01*
X274003Y-370566D01*
X274007Y-370606D01*
X274011Y-370640D01*
X274014Y-370666D01*
Y-370703D01*
X274007Y-370825D01*
X273989Y-370943D01*
X273966Y-371047D01*
X273952Y-371095D01*
X273937Y-371139D01*
X273922Y-371180D01*
X273907Y-371217D01*
X273896Y-371246D01*
X273885Y-371276D01*
X273874Y-371294D01*
X273866Y-371309D01*
X273863Y-371320D01*
X273859Y-371324D01*
X273796Y-371424D01*
X273722Y-371509D01*
X273648Y-371583D01*
X273574Y-371646D01*
X273507Y-371694D01*
X273478Y-371713D01*
X273452Y-371727D01*
X273434Y-371742D01*
X273419Y-371750D01*
X273408Y-371753D01*
X273404Y-371757D01*
X273289Y-371809D01*
X273171Y-371846D01*
X273052Y-371872D01*
X272945Y-371890D01*
X272897Y-371898D01*
X272849Y-371901D01*
X272812Y-371905D01*
X272775D01*
X272749Y-371909D01*
X272727D01*
X272712D01*
X272708D01*
X272575Y-371901D01*
X272446Y-371886D01*
X272331Y-371868D01*
X272275Y-371853D01*
X272227Y-371842D01*
X272183Y-371831D01*
X272142Y-371816D01*
X272105Y-371805D01*
X272076Y-371798D01*
X272054Y-371787D01*
X272035Y-371783D01*
X272024Y-371776D01*
X272020D01*
X271909Y-371720D01*
X271809Y-371657D01*
X271724Y-371590D01*
X271691Y-371557D01*
X271657Y-371528D01*
X271628Y-371498D01*
X271602Y-371468D01*
X271580Y-371443D01*
X271565Y-371420D01*
X271550Y-371406D01*
X271539Y-371391D01*
X271535Y-371383D01*
X271532Y-371380D01*
X271502Y-371328D01*
X271476Y-371276D01*
X271436Y-371165D01*
X271406Y-371054D01*
X271387Y-370947D01*
X271380Y-370895D01*
X271373Y-370850D01*
X271369Y-370810D01*
Y-370777D01*
X271365Y-370747D01*
Y-370706D01*
X271369Y-370632D01*
X271376Y-370562D01*
X271384Y-370495D01*
X271398Y-370432D01*
X271417Y-370373D01*
X271436Y-370318D01*
X271454Y-370266D01*
X271476Y-370218D01*
X271495Y-370177D01*
X271513Y-370136D01*
X271532Y-370107D01*
X271550Y-370077D01*
X271565Y-370059D01*
X271572Y-370040D01*
X271580Y-370033D01*
X271584Y-370029D01*
X271628Y-369977D01*
X271672Y-369933D01*
X271724Y-369892D01*
X271776Y-369851D01*
X271880Y-369785D01*
X271983Y-369733D01*
X272031Y-369711D01*
X272076Y-369692D01*
X272116Y-369678D01*
X272150Y-369667D01*
X272179Y-369655D01*
X272201Y-369648D01*
X272216Y-369644D01*
X272220D01*
X272305Y-369985D01*
D02*
G37*
G36*
X206064Y-377842D02*
X207721D01*
Y-378097D01*
X206064Y-379270D01*
X205775D01*
Y-378156D01*
X205161D01*
Y-377842D01*
X205775D01*
Y-377494D01*
X206064D01*
Y-377842D01*
D02*
G37*
G36*
Y-379832D02*
X207721D01*
Y-380088D01*
X206064Y-381260D01*
X205775D01*
Y-380147D01*
X205161D01*
Y-379832D01*
X205775D01*
Y-379485D01*
X206064D01*
Y-379832D01*
D02*
G37*
G36*
X206056Y-381782D02*
X205997Y-381797D01*
X205941Y-381816D01*
X205890Y-381834D01*
X205841Y-381853D01*
X205797Y-381875D01*
X205760Y-381897D01*
X205723Y-381923D01*
X205690Y-381945D01*
X205660Y-381963D01*
X205638Y-381986D01*
X205616Y-382004D01*
X205597Y-382019D01*
X205586Y-382034D01*
X205575Y-382045D01*
X205571Y-382049D01*
X205568Y-382052D01*
X205538Y-382089D01*
X205516Y-382130D01*
X205475Y-382211D01*
X205446Y-382289D01*
X205427Y-382367D01*
X205412Y-382433D01*
X205409Y-382459D01*
Y-382485D01*
X205405Y-382507D01*
Y-382533D01*
X205409Y-382618D01*
X205423Y-382700D01*
X205442Y-382774D01*
X205464Y-382840D01*
X205486Y-382892D01*
X205497Y-382914D01*
X205505Y-382933D01*
X205512Y-382948D01*
X205520Y-382959D01*
X205523Y-382966D01*
Y-382970D01*
X205575Y-383040D01*
X205631Y-383099D01*
X205694Y-383151D01*
X205753Y-383192D01*
X205804Y-383225D01*
X205849Y-383247D01*
X205867Y-383255D01*
X205878Y-383262D01*
X205886Y-383266D01*
X205890D01*
X205986Y-383295D01*
X206082Y-383318D01*
X206178Y-383336D01*
X206267Y-383347D01*
X206308Y-383351D01*
X206345Y-383355D01*
X206378D01*
X206404Y-383358D01*
X206426D01*
X206445D01*
X206456D01*
X206459D01*
X206556Y-383355D01*
X206644Y-383347D01*
X206726Y-383332D01*
X206800Y-383318D01*
X206863Y-383307D01*
X206889Y-383299D01*
X206911Y-383292D01*
X206929Y-383288D01*
X206940Y-383284D01*
X206948Y-383281D01*
X206951D01*
X207037Y-383244D01*
X207114Y-383203D01*
X207177Y-383159D01*
X207233Y-383110D01*
X207277Y-383070D01*
X207307Y-383036D01*
X207325Y-383011D01*
X207333Y-383007D01*
Y-383003D01*
X207381Y-382926D01*
X207418Y-382840D01*
X207444Y-382759D01*
X207458Y-382681D01*
X207470Y-382611D01*
X207473Y-382581D01*
Y-382556D01*
X207477Y-382537D01*
Y-382507D01*
X207473Y-382415D01*
X207458Y-382330D01*
X207436Y-382259D01*
X207414Y-382197D01*
X207388Y-382149D01*
X207370Y-382112D01*
X207355Y-382089D01*
X207347Y-382082D01*
X207292Y-382023D01*
X207229Y-381967D01*
X207162Y-381923D01*
X207096Y-381886D01*
X207037Y-381856D01*
X207007Y-381845D01*
X206985Y-381838D01*
X206966Y-381830D01*
X206951Y-381823D01*
X206944Y-381819D01*
X206940D01*
X207018Y-381486D01*
X207085Y-381508D01*
X207144Y-381531D01*
X207199Y-381560D01*
X207255Y-381586D01*
X207303Y-381616D01*
X207347Y-381649D01*
X207392Y-381679D01*
X207429Y-381708D01*
X207458Y-381738D01*
X207488Y-381764D01*
X207514Y-381790D01*
X207532Y-381808D01*
X207551Y-381827D01*
X207562Y-381841D01*
X207566Y-381849D01*
X207569Y-381853D01*
X207603Y-381904D01*
X207636Y-381956D01*
X207662Y-382008D01*
X207684Y-382063D01*
X207717Y-382174D01*
X207740Y-382274D01*
X207751Y-382322D01*
X207754Y-382363D01*
X207758Y-382404D01*
X207762Y-382437D01*
X207766Y-382463D01*
Y-382500D01*
X207758Y-382622D01*
X207740Y-382740D01*
X207717Y-382844D01*
X207703Y-382892D01*
X207688Y-382937D01*
X207673Y-382977D01*
X207658Y-383014D01*
X207647Y-383044D01*
X207636Y-383073D01*
X207625Y-383092D01*
X207617Y-383107D01*
X207614Y-383118D01*
X207610Y-383122D01*
X207547Y-383222D01*
X207473Y-383307D01*
X207399Y-383381D01*
X207325Y-383443D01*
X207259Y-383492D01*
X207229Y-383510D01*
X207203Y-383525D01*
X207185Y-383540D01*
X207170Y-383547D01*
X207159Y-383551D01*
X207155Y-383555D01*
X207040Y-383606D01*
X206922Y-383643D01*
X206803Y-383669D01*
X206696Y-383688D01*
X206648Y-383695D01*
X206600Y-383699D01*
X206563Y-383702D01*
X206526D01*
X206500Y-383706D01*
X206478D01*
X206463D01*
X206459D01*
X206326Y-383699D01*
X206197Y-383684D01*
X206082Y-383665D01*
X206027Y-383651D01*
X205978Y-383640D01*
X205934Y-383629D01*
X205893Y-383614D01*
X205856Y-383603D01*
X205827Y-383595D01*
X205804Y-383584D01*
X205786Y-383580D01*
X205775Y-383573D01*
X205771D01*
X205660Y-383518D01*
X205560Y-383455D01*
X205475Y-383388D01*
X205442Y-383355D01*
X205409Y-383325D01*
X205379Y-383295D01*
X205353Y-383266D01*
X205331Y-383240D01*
X205316Y-383218D01*
X205301Y-383203D01*
X205290Y-383188D01*
X205287Y-383181D01*
X205283Y-383177D01*
X205253Y-383125D01*
X205227Y-383073D01*
X205187Y-382962D01*
X205157Y-382852D01*
X205138Y-382744D01*
X205131Y-382692D01*
X205124Y-382648D01*
X205120Y-382607D01*
Y-382574D01*
X205116Y-382544D01*
Y-382504D01*
X205120Y-382430D01*
X205127Y-382359D01*
X205135Y-382293D01*
X205150Y-382230D01*
X205168Y-382171D01*
X205187Y-382115D01*
X205205Y-382063D01*
X205227Y-382015D01*
X205246Y-381975D01*
X205264Y-381934D01*
X205283Y-381904D01*
X205301Y-381875D01*
X205316Y-381856D01*
X205324Y-381838D01*
X205331Y-381830D01*
X205335Y-381827D01*
X205379Y-381775D01*
X205423Y-381730D01*
X205475Y-381690D01*
X205527Y-381649D01*
X205631Y-381582D01*
X205734Y-381531D01*
X205782Y-381508D01*
X205827Y-381490D01*
X205867Y-381475D01*
X205901Y-381464D01*
X205930Y-381453D01*
X205953Y-381446D01*
X205967Y-381442D01*
X205971D01*
X206056Y-381782D01*
D02*
G37*
G36*
X209342Y-365698D02*
X209405Y-365706D01*
X209468Y-365717D01*
X209523Y-365732D01*
X209575Y-365750D01*
X209627Y-365769D01*
X209671Y-365791D01*
X209712Y-365809D01*
X209749Y-365831D01*
X209782Y-365854D01*
X209808Y-365872D01*
X209834Y-365891D01*
X209853Y-365905D01*
X209864Y-365917D01*
X209871Y-365924D01*
X209875Y-365928D01*
X209915Y-365972D01*
X209952Y-366017D01*
X209982Y-366065D01*
X210008Y-366113D01*
X210034Y-366161D01*
X210052Y-366209D01*
X210078Y-366298D01*
X210089Y-366338D01*
X210097Y-366375D01*
X210101Y-366409D01*
X210104Y-366438D01*
X210108Y-366460D01*
Y-366542D01*
X210101Y-366586D01*
X210082Y-366675D01*
X210056Y-366757D01*
X210027Y-366830D01*
X209997Y-366890D01*
X209982Y-366916D01*
X209971Y-366938D01*
X209960Y-366956D01*
X209952Y-366967D01*
X209949Y-366975D01*
X209945Y-366979D01*
X210637Y-366842D01*
Y-365817D01*
X210937D01*
Y-367090D01*
X209619Y-367337D01*
X209579Y-367041D01*
X209619Y-367016D01*
X209653Y-366982D01*
X209686Y-366953D01*
X209712Y-366923D01*
X209731Y-366893D01*
X209749Y-366871D01*
X209756Y-366856D01*
X209760Y-366853D01*
X209782Y-366805D01*
X209801Y-366757D01*
X209812Y-366712D01*
X209823Y-366668D01*
X209827Y-366631D01*
X209830Y-366601D01*
Y-366531D01*
X209823Y-366486D01*
X209805Y-366409D01*
X209779Y-366342D01*
X209753Y-366283D01*
X209723Y-366238D01*
X209697Y-366205D01*
X209679Y-366187D01*
X209675Y-366179D01*
X209671D01*
X209608Y-366127D01*
X209542Y-366090D01*
X209472Y-366065D01*
X209401Y-366046D01*
X209342Y-366035D01*
X209316Y-366031D01*
X209294D01*
X209275Y-366028D01*
X209261D01*
X209253D01*
X209249D01*
X209198D01*
X209150Y-366035D01*
X209057Y-366054D01*
X208979Y-366079D01*
X208916Y-366105D01*
X208865Y-366135D01*
X208824Y-366161D01*
X208813Y-366172D01*
X208802Y-366179D01*
X208798Y-366183D01*
X208794Y-366187D01*
X208765Y-366216D01*
X208739Y-366246D01*
X208695Y-366313D01*
X208665Y-366375D01*
X208646Y-366438D01*
X208632Y-366490D01*
X208628Y-366534D01*
X208624Y-366549D01*
Y-366571D01*
X208628Y-366642D01*
X208643Y-366705D01*
X208661Y-366760D01*
X208683Y-366805D01*
X208706Y-366845D01*
X208724Y-366875D01*
X208739Y-366890D01*
X208743Y-366897D01*
X208794Y-366941D01*
X208850Y-366979D01*
X208913Y-367008D01*
X208968Y-367030D01*
X209024Y-367045D01*
X209065Y-367056D01*
X209083Y-367060D01*
X209094Y-367064D01*
X209102D01*
X209105D01*
X209079Y-367393D01*
X209020Y-367386D01*
X208965Y-367374D01*
X208861Y-367341D01*
X208772Y-367300D01*
X208732Y-367278D01*
X208698Y-367256D01*
X208665Y-367237D01*
X208635Y-367215D01*
X208613Y-367197D01*
X208595Y-367178D01*
X208580Y-367163D01*
X208565Y-367156D01*
X208561Y-367149D01*
X208558Y-367145D01*
X208524Y-367101D01*
X208495Y-367056D01*
X208469Y-367008D01*
X208447Y-366960D01*
X208413Y-366867D01*
X208391Y-366775D01*
X208380Y-366734D01*
X208376Y-366694D01*
X208373Y-366660D01*
X208369Y-366631D01*
X208365Y-366605D01*
Y-366571D01*
X208369Y-366494D01*
X208380Y-366420D01*
X208395Y-366350D01*
X208413Y-366287D01*
X208439Y-366227D01*
X208465Y-366172D01*
X208491Y-366120D01*
X208521Y-366076D01*
X208550Y-366035D01*
X208576Y-365998D01*
X208606Y-365968D01*
X208628Y-365943D01*
X208646Y-365924D01*
X208661Y-365909D01*
X208672Y-365902D01*
X208676Y-365898D01*
X208724Y-365861D01*
X208776Y-365831D01*
X208824Y-365802D01*
X208876Y-365780D01*
X208976Y-365743D01*
X209072Y-365721D01*
X209113Y-365713D01*
X209153Y-365706D01*
X209187Y-365702D01*
X209216Y-365698D01*
X209242Y-365695D01*
X209261D01*
X209272D01*
X209275D01*
X209342Y-365698D01*
D02*
G37*
G36*
X209312Y-368063D02*
X210970D01*
Y-368318D01*
X209312Y-369491D01*
X209024D01*
Y-368377D01*
X208410D01*
Y-368063D01*
X209024D01*
Y-367715D01*
X209312D01*
Y-368063D01*
D02*
G37*
G36*
X209305Y-370012D02*
X209246Y-370027D01*
X209190Y-370046D01*
X209138Y-370064D01*
X209090Y-370083D01*
X209046Y-370105D01*
X209009Y-370127D01*
X208972Y-370153D01*
X208939Y-370175D01*
X208909Y-370194D01*
X208887Y-370216D01*
X208865Y-370234D01*
X208846Y-370249D01*
X208835Y-370264D01*
X208824Y-370275D01*
X208820Y-370279D01*
X208817Y-370283D01*
X208787Y-370320D01*
X208765Y-370360D01*
X208724Y-370442D01*
X208695Y-370519D01*
X208676Y-370597D01*
X208661Y-370664D01*
X208658Y-370690D01*
Y-370715D01*
X208654Y-370738D01*
Y-370764D01*
X208658Y-370849D01*
X208672Y-370930D01*
X208691Y-371004D01*
X208713Y-371071D01*
X208735Y-371123D01*
X208746Y-371145D01*
X208754Y-371163D01*
X208761Y-371178D01*
X208769Y-371189D01*
X208772Y-371197D01*
Y-371200D01*
X208824Y-371270D01*
X208879Y-371330D01*
X208942Y-371381D01*
X209002Y-371422D01*
X209053Y-371456D01*
X209098Y-371478D01*
X209116Y-371485D01*
X209127Y-371493D01*
X209135Y-371496D01*
X209138D01*
X209235Y-371526D01*
X209331Y-371548D01*
X209427Y-371567D01*
X209516Y-371578D01*
X209557Y-371581D01*
X209594Y-371585D01*
X209627D01*
X209653Y-371589D01*
X209675D01*
X209694D01*
X209705D01*
X209708D01*
X209805Y-371585D01*
X209893Y-371578D01*
X209975Y-371563D01*
X210049Y-371548D01*
X210112Y-371537D01*
X210138Y-371530D01*
X210160Y-371522D01*
X210178Y-371518D01*
X210189Y-371515D01*
X210197Y-371511D01*
X210200D01*
X210285Y-371474D01*
X210363Y-371433D01*
X210426Y-371389D01*
X210482Y-371341D01*
X210526Y-371300D01*
X210556Y-371267D01*
X210574Y-371241D01*
X210581Y-371237D01*
Y-371234D01*
X210630Y-371156D01*
X210667Y-371071D01*
X210693Y-370989D01*
X210707Y-370912D01*
X210718Y-370841D01*
X210722Y-370812D01*
Y-370786D01*
X210726Y-370767D01*
Y-370738D01*
X210722Y-370645D01*
X210707Y-370560D01*
X210685Y-370490D01*
X210663Y-370427D01*
X210637Y-370379D01*
X210618Y-370342D01*
X210604Y-370320D01*
X210596Y-370312D01*
X210541Y-370253D01*
X210478Y-370198D01*
X210411Y-370153D01*
X210345Y-370116D01*
X210285Y-370087D01*
X210256Y-370075D01*
X210234Y-370068D01*
X210215Y-370061D01*
X210200Y-370053D01*
X210193Y-370050D01*
X210189D01*
X210267Y-369717D01*
X210334Y-369739D01*
X210393Y-369761D01*
X210448Y-369791D01*
X210504Y-369816D01*
X210552Y-369846D01*
X210596Y-369879D01*
X210641Y-369909D01*
X210678Y-369938D01*
X210707Y-369968D01*
X210737Y-369994D01*
X210763Y-370020D01*
X210781Y-370038D01*
X210800Y-370057D01*
X210811Y-370072D01*
X210815Y-370079D01*
X210818Y-370083D01*
X210852Y-370135D01*
X210885Y-370186D01*
X210911Y-370238D01*
X210933Y-370294D01*
X210966Y-370405D01*
X210988Y-370505D01*
X211000Y-370553D01*
X211003Y-370593D01*
X211007Y-370634D01*
X211011Y-370667D01*
X211014Y-370693D01*
Y-370730D01*
X211007Y-370852D01*
X210988Y-370971D01*
X210966Y-371074D01*
X210951Y-371123D01*
X210937Y-371167D01*
X210922Y-371208D01*
X210907Y-371245D01*
X210896Y-371274D01*
X210885Y-371304D01*
X210874Y-371322D01*
X210866Y-371337D01*
X210863Y-371348D01*
X210859Y-371352D01*
X210796Y-371452D01*
X210722Y-371537D01*
X210648Y-371611D01*
X210574Y-371674D01*
X210507Y-371722D01*
X210478Y-371740D01*
X210452Y-371755D01*
X210434Y-371770D01*
X210419Y-371777D01*
X210408Y-371781D01*
X210404Y-371785D01*
X210289Y-371837D01*
X210171Y-371874D01*
X210052Y-371900D01*
X209945Y-371918D01*
X209897Y-371925D01*
X209849Y-371929D01*
X209812Y-371933D01*
X209775D01*
X209749Y-371936D01*
X209727D01*
X209712D01*
X209708D01*
X209575Y-371929D01*
X209446Y-371914D01*
X209331Y-371896D01*
X209275Y-371881D01*
X209227Y-371870D01*
X209183Y-371859D01*
X209142Y-371844D01*
X209105Y-371833D01*
X209076Y-371826D01*
X209053Y-371814D01*
X209035Y-371811D01*
X209024Y-371803D01*
X209020D01*
X208909Y-371748D01*
X208809Y-371685D01*
X208724Y-371618D01*
X208691Y-371585D01*
X208658Y-371555D01*
X208628Y-371526D01*
X208602Y-371496D01*
X208580Y-371470D01*
X208565Y-371448D01*
X208550Y-371433D01*
X208539Y-371418D01*
X208535Y-371411D01*
X208532Y-371407D01*
X208502Y-371356D01*
X208476Y-371304D01*
X208436Y-371193D01*
X208406Y-371082D01*
X208387Y-370974D01*
X208380Y-370923D01*
X208373Y-370878D01*
X208369Y-370838D01*
Y-370804D01*
X208365Y-370775D01*
Y-370734D01*
X208369Y-370660D01*
X208376Y-370590D01*
X208384Y-370523D01*
X208399Y-370460D01*
X208417Y-370401D01*
X208436Y-370345D01*
X208454Y-370294D01*
X208476Y-370246D01*
X208495Y-370205D01*
X208513Y-370164D01*
X208532Y-370135D01*
X208550Y-370105D01*
X208565Y-370087D01*
X208572Y-370068D01*
X208580Y-370061D01*
X208583Y-370057D01*
X208628Y-370005D01*
X208672Y-369961D01*
X208724Y-369920D01*
X208776Y-369879D01*
X208879Y-369813D01*
X208983Y-369761D01*
X209031Y-369739D01*
X209076Y-369720D01*
X209116Y-369705D01*
X209150Y-369694D01*
X209179Y-369683D01*
X209201Y-369676D01*
X209216Y-369672D01*
X209220D01*
X209305Y-370012D01*
D02*
G37*
G36*
X217956Y-377492D02*
X218019Y-377499D01*
X218082Y-377510D01*
X218137Y-377522D01*
X218189Y-377540D01*
X218241Y-377559D01*
X218285Y-377577D01*
X218326Y-377599D01*
X218363Y-377622D01*
X218396Y-377640D01*
X218422Y-377659D01*
X218448Y-377677D01*
X218467Y-377688D01*
X218478Y-377699D01*
X218485Y-377707D01*
X218489Y-377710D01*
X218530Y-377751D01*
X218567Y-377795D01*
X218596Y-377843D01*
X218622Y-377888D01*
X218648Y-377932D01*
X218667Y-377977D01*
X218692Y-378062D01*
X218704Y-378099D01*
X218711Y-378136D01*
X218715Y-378165D01*
X218718Y-378195D01*
X218722Y-378217D01*
Y-378247D01*
X218718Y-378313D01*
X218707Y-378376D01*
X218696Y-378435D01*
X218681Y-378487D01*
X218663Y-378532D01*
X218652Y-378565D01*
X218641Y-378587D01*
X218637Y-378591D01*
Y-378595D01*
X218600Y-378654D01*
X218559Y-378706D01*
X218519Y-378754D01*
X218474Y-378791D01*
X218437Y-378824D01*
X218408Y-378850D01*
X218385Y-378865D01*
X218382Y-378868D01*
X218448D01*
X218515Y-378865D01*
X218574Y-378861D01*
X218633Y-378854D01*
X218685Y-378850D01*
X218733Y-378842D01*
X218778Y-378835D01*
X218818Y-378824D01*
X218855Y-378817D01*
X218885Y-378809D01*
X218911Y-378802D01*
X218933Y-378798D01*
X218948Y-378791D01*
X218959Y-378787D01*
X218966Y-378783D01*
X218970D01*
X219044Y-378746D01*
X219111Y-378709D01*
X219162Y-378669D01*
X219207Y-378632D01*
X219244Y-378598D01*
X219270Y-378572D01*
X219285Y-378554D01*
X219288Y-378547D01*
X219318Y-378502D01*
X219336Y-378458D01*
X219351Y-378413D01*
X219362Y-378369D01*
X219370Y-378336D01*
X219373Y-378306D01*
Y-378280D01*
X219366Y-378214D01*
X219351Y-378151D01*
X219329Y-378099D01*
X219307Y-378051D01*
X219281Y-378014D01*
X219259Y-377988D01*
X219244Y-377973D01*
X219236Y-377966D01*
X219203Y-377940D01*
X219162Y-377914D01*
X219118Y-377892D01*
X219074Y-377877D01*
X219033Y-377862D01*
X219000Y-377851D01*
X218977Y-377847D01*
X218974Y-377843D01*
X218970D01*
X218996Y-377529D01*
X219099Y-377551D01*
X219192Y-377585D01*
X219273Y-377622D01*
X219340Y-377662D01*
X219392Y-377703D01*
X219414Y-377718D01*
X219432Y-377736D01*
X219444Y-377747D01*
X219455Y-377758D01*
X219458Y-377762D01*
X219462Y-377766D01*
X219492Y-377803D01*
X219517Y-377843D01*
X219562Y-377925D01*
X219592Y-378006D01*
X219610Y-378084D01*
X219625Y-378154D01*
X219629Y-378184D01*
Y-378210D01*
X219632Y-378232D01*
Y-378262D01*
X219629Y-378336D01*
X219621Y-378406D01*
X219606Y-378472D01*
X219588Y-378535D01*
X219562Y-378591D01*
X219540Y-378646D01*
X219510Y-378695D01*
X219484Y-378739D01*
X219458Y-378776D01*
X219429Y-378813D01*
X219407Y-378842D01*
X219384Y-378865D01*
X219362Y-378883D01*
X219347Y-378898D01*
X219340Y-378905D01*
X219336Y-378909D01*
X219270Y-378957D01*
X219192Y-378998D01*
X219111Y-379035D01*
X219025Y-379068D01*
X218937Y-379094D01*
X218848Y-379116D01*
X218755Y-379135D01*
X218670Y-379150D01*
X218585Y-379161D01*
X218508Y-379168D01*
X218437Y-379175D01*
X218378Y-379179D01*
X218326D01*
X218289Y-379183D01*
X218274D01*
X218263D01*
X218260D01*
X218256D01*
X218137Y-379179D01*
X218026Y-379172D01*
X217923Y-379161D01*
X217827Y-379142D01*
X217742Y-379124D01*
X217664Y-379105D01*
X217594Y-379083D01*
X217531Y-379057D01*
X217479Y-379035D01*
X217431Y-379013D01*
X217394Y-378994D01*
X217360Y-378972D01*
X217335Y-378957D01*
X217320Y-378946D01*
X217309Y-378939D01*
X217305Y-378935D01*
X217253Y-378887D01*
X217209Y-378835D01*
X217172Y-378783D01*
X217139Y-378731D01*
X217109Y-378676D01*
X217087Y-378624D01*
X217068Y-378572D01*
X217053Y-378521D01*
X217042Y-378476D01*
X217031Y-378432D01*
X217024Y-378395D01*
X217020Y-378362D01*
Y-378332D01*
X217016Y-378313D01*
Y-378295D01*
X217020Y-378210D01*
X217035Y-378132D01*
X217050Y-378062D01*
X217072Y-377999D01*
X217090Y-377951D01*
X217109Y-377914D01*
X217113Y-377899D01*
X217120Y-377888D01*
X217124Y-377884D01*
Y-377881D01*
X217168Y-377818D01*
X217220Y-377758D01*
X217272Y-377710D01*
X217323Y-377670D01*
X217372Y-377636D01*
X217409Y-377614D01*
X217423Y-377607D01*
X217435Y-377599D01*
X217438Y-377596D01*
X217442D01*
X217519Y-377559D01*
X217601Y-377533D01*
X217675Y-377514D01*
X217745Y-377503D01*
X217804Y-377492D01*
X217827D01*
X217849Y-377488D01*
X217867D01*
X217879D01*
X217886D01*
X217890D01*
X217956Y-377492D01*
D02*
G37*
G36*
X217964Y-379838D02*
X219621D01*
Y-380093D01*
X217964Y-381266D01*
X217675D01*
Y-380152D01*
X217061D01*
Y-379838D01*
X217675D01*
Y-379490D01*
X217964D01*
Y-379838D01*
D02*
G37*
G36*
X217956Y-381788D02*
X217897Y-381803D01*
X217841Y-381821D01*
X217790Y-381839D01*
X217742Y-381858D01*
X217697Y-381880D01*
X217660Y-381902D01*
X217623Y-381928D01*
X217590Y-381950D01*
X217560Y-381969D01*
X217538Y-381991D01*
X217516Y-382010D01*
X217497Y-382025D01*
X217486Y-382039D01*
X217475Y-382050D01*
X217472Y-382054D01*
X217468Y-382058D01*
X217438Y-382095D01*
X217416Y-382136D01*
X217375Y-382217D01*
X217346Y-382295D01*
X217327Y-382372D01*
X217312Y-382439D01*
X217309Y-382465D01*
Y-382491D01*
X217305Y-382513D01*
Y-382539D01*
X217309Y-382624D01*
X217323Y-382705D01*
X217342Y-382779D01*
X217364Y-382846D01*
X217386Y-382898D01*
X217397Y-382920D01*
X217405Y-382938D01*
X217412Y-382953D01*
X217420Y-382964D01*
X217423Y-382972D01*
Y-382975D01*
X217475Y-383046D01*
X217531Y-383105D01*
X217594Y-383157D01*
X217653Y-383197D01*
X217705Y-383231D01*
X217749Y-383253D01*
X217768Y-383260D01*
X217778Y-383268D01*
X217786Y-383271D01*
X217790D01*
X217886Y-383301D01*
X217982Y-383323D01*
X218078Y-383342D01*
X218167Y-383353D01*
X218208Y-383356D01*
X218245Y-383360D01*
X218278D01*
X218304Y-383364D01*
X218326D01*
X218345D01*
X218356D01*
X218359D01*
X218456Y-383360D01*
X218545Y-383353D01*
X218626Y-383338D01*
X218700Y-383323D01*
X218763Y-383312D01*
X218789Y-383305D01*
X218811Y-383297D01*
X218829Y-383294D01*
X218841Y-383290D01*
X218848Y-383286D01*
X218851D01*
X218937Y-383249D01*
X219014Y-383208D01*
X219077Y-383164D01*
X219133Y-383116D01*
X219177Y-383075D01*
X219207Y-383042D01*
X219225Y-383016D01*
X219233Y-383012D01*
Y-383009D01*
X219281Y-382931D01*
X219318Y-382846D01*
X219344Y-382765D01*
X219358Y-382687D01*
X219370Y-382616D01*
X219373Y-382587D01*
Y-382561D01*
X219377Y-382542D01*
Y-382513D01*
X219373Y-382420D01*
X219358Y-382335D01*
X219336Y-382265D01*
X219314Y-382202D01*
X219288Y-382154D01*
X219270Y-382117D01*
X219255Y-382095D01*
X219247Y-382087D01*
X219192Y-382028D01*
X219129Y-381973D01*
X219062Y-381928D01*
X218996Y-381891D01*
X218937Y-381862D01*
X218907Y-381851D01*
X218885Y-381843D01*
X218866Y-381836D01*
X218851Y-381828D01*
X218844Y-381825D01*
X218841D01*
X218918Y-381492D01*
X218985Y-381514D01*
X219044Y-381536D01*
X219099Y-381566D01*
X219155Y-381592D01*
X219203Y-381621D01*
X219247Y-381655D01*
X219292Y-381684D01*
X219329Y-381714D01*
X219358Y-381743D01*
X219388Y-381769D01*
X219414Y-381795D01*
X219432Y-381814D01*
X219451Y-381832D01*
X219462Y-381847D01*
X219466Y-381854D01*
X219469Y-381858D01*
X219503Y-381910D01*
X219536Y-381962D01*
X219562Y-382013D01*
X219584Y-382069D01*
X219618Y-382180D01*
X219640Y-382280D01*
X219651Y-382328D01*
X219654Y-382369D01*
X219658Y-382409D01*
X219662Y-382443D01*
X219666Y-382469D01*
Y-382505D01*
X219658Y-382628D01*
X219640Y-382746D01*
X219618Y-382850D01*
X219603Y-382898D01*
X219588Y-382942D01*
X219573Y-382983D01*
X219558Y-383020D01*
X219547Y-383049D01*
X219536Y-383079D01*
X219525Y-383098D01*
X219517Y-383112D01*
X219514Y-383123D01*
X219510Y-383127D01*
X219447Y-383227D01*
X219373Y-383312D01*
X219299Y-383386D01*
X219225Y-383449D01*
X219159Y-383497D01*
X219129Y-383516D01*
X219103Y-383530D01*
X219085Y-383545D01*
X219070Y-383553D01*
X219059Y-383556D01*
X219055Y-383560D01*
X218940Y-383612D01*
X218822Y-383649D01*
X218704Y-383675D01*
X218596Y-383693D01*
X218548Y-383701D01*
X218500Y-383704D01*
X218463Y-383708D01*
X218426D01*
X218400Y-383712D01*
X218378D01*
X218363D01*
X218359D01*
X218226Y-383704D01*
X218097Y-383689D01*
X217982Y-383671D01*
X217927Y-383656D01*
X217879Y-383645D01*
X217834Y-383634D01*
X217793Y-383619D01*
X217756Y-383608D01*
X217727Y-383601D01*
X217705Y-383590D01*
X217686Y-383586D01*
X217675Y-383578D01*
X217671D01*
X217560Y-383523D01*
X217460Y-383460D01*
X217375Y-383394D01*
X217342Y-383360D01*
X217309Y-383331D01*
X217279Y-383301D01*
X217253Y-383271D01*
X217231Y-383245D01*
X217216Y-383223D01*
X217201Y-383208D01*
X217190Y-383194D01*
X217186Y-383186D01*
X217183Y-383183D01*
X217153Y-383131D01*
X217127Y-383079D01*
X217087Y-382968D01*
X217057Y-382857D01*
X217038Y-382750D01*
X217031Y-382698D01*
X217024Y-382653D01*
X217020Y-382613D01*
Y-382579D01*
X217016Y-382550D01*
Y-382509D01*
X217020Y-382435D01*
X217027Y-382365D01*
X217035Y-382298D01*
X217050Y-382235D01*
X217068Y-382176D01*
X217087Y-382121D01*
X217105Y-382069D01*
X217127Y-382021D01*
X217146Y-381980D01*
X217164Y-381939D01*
X217183Y-381910D01*
X217201Y-381880D01*
X217216Y-381862D01*
X217224Y-381843D01*
X217231Y-381836D01*
X217235Y-381832D01*
X217279Y-381780D01*
X217323Y-381736D01*
X217375Y-381695D01*
X217427Y-381655D01*
X217531Y-381588D01*
X217634Y-381536D01*
X217682Y-381514D01*
X217727Y-381495D01*
X217768Y-381481D01*
X217801Y-381469D01*
X217830Y-381458D01*
X217853Y-381451D01*
X217867Y-381447D01*
X217871D01*
X217956Y-381788D01*
D02*
G37*
G36*
X223137Y-367343D02*
X222833D01*
Y-366089D01*
X222726Y-366177D01*
X222611Y-366263D01*
X222500Y-366336D01*
X222393Y-366407D01*
X222345Y-366436D01*
X222301Y-366462D01*
X222260Y-366488D01*
X222227Y-366507D01*
X222197Y-366522D01*
X222179Y-366533D01*
X222164Y-366540D01*
X222160Y-366544D01*
X222012Y-366618D01*
X221864Y-366684D01*
X221723Y-366740D01*
X221660Y-366762D01*
X221598Y-366784D01*
X221542Y-366806D01*
X221490Y-366821D01*
X221446Y-366836D01*
X221409Y-366847D01*
X221376Y-366858D01*
X221353Y-366866D01*
X221339Y-366869D01*
X221335D01*
X221183Y-366906D01*
X221109Y-366921D01*
X221042Y-366932D01*
X220980Y-366943D01*
X220917Y-366954D01*
X220865Y-366962D01*
X220813Y-366969D01*
X220769Y-366973D01*
X220728Y-366977D01*
X220691Y-366980D01*
X220661D01*
X220639Y-366984D01*
X220624D01*
X220613D01*
X220610D01*
Y-366662D01*
X220750Y-366651D01*
X220880Y-366633D01*
X220998Y-366614D01*
X221054Y-366603D01*
X221106Y-366592D01*
X221150Y-366584D01*
X221191Y-366573D01*
X221228Y-366566D01*
X221257Y-366559D01*
X221279Y-366551D01*
X221298Y-366547D01*
X221309Y-366544D01*
X221313D01*
X221483Y-366488D01*
X221642Y-366429D01*
X221720Y-366399D01*
X221794Y-366370D01*
X221860Y-366336D01*
X221927Y-366307D01*
X221986Y-366281D01*
X222038Y-366255D01*
X222082Y-366233D01*
X222123Y-366214D01*
X222156Y-366196D01*
X222179Y-366185D01*
X222193Y-366177D01*
X222197Y-366174D01*
X222275Y-366129D01*
X222352Y-366085D01*
X222423Y-366040D01*
X222489Y-365996D01*
X222549Y-365955D01*
X222608Y-365915D01*
X222659Y-365874D01*
X222704Y-365841D01*
X222748Y-365807D01*
X222785Y-365778D01*
X222815Y-365748D01*
X222841Y-365726D01*
X222863Y-365711D01*
X222878Y-365696D01*
X222885Y-365689D01*
X222889Y-365685D01*
X223137D01*
Y-367343D01*
D02*
G37*
G36*
X221512Y-368035D02*
X223170D01*
Y-368290D01*
X221512Y-369463D01*
X221224D01*
Y-368349D01*
X220610D01*
Y-368035D01*
X221224D01*
Y-367687D01*
X221512D01*
Y-368035D01*
D02*
G37*
G36*
X221505Y-369985D02*
X221446Y-370000D01*
X221390Y-370018D01*
X221339Y-370037D01*
X221290Y-370055D01*
X221246Y-370077D01*
X221209Y-370099D01*
X221172Y-370125D01*
X221139Y-370147D01*
X221109Y-370166D01*
X221087Y-370188D01*
X221065Y-370207D01*
X221046Y-370221D01*
X221035Y-370236D01*
X221024Y-370247D01*
X221020Y-370251D01*
X221017Y-370255D01*
X220987Y-370292D01*
X220965Y-370333D01*
X220924Y-370414D01*
X220895Y-370492D01*
X220876Y-370569D01*
X220861Y-370636D01*
X220858Y-370662D01*
Y-370688D01*
X220854Y-370710D01*
Y-370736D01*
X220858Y-370821D01*
X220872Y-370902D01*
X220891Y-370976D01*
X220913Y-371043D01*
X220935Y-371095D01*
X220946Y-371117D01*
X220954Y-371135D01*
X220961Y-371150D01*
X220969Y-371161D01*
X220972Y-371169D01*
Y-371172D01*
X221024Y-371243D01*
X221080Y-371302D01*
X221143Y-371354D01*
X221202Y-371394D01*
X221253Y-371428D01*
X221298Y-371450D01*
X221316Y-371457D01*
X221327Y-371465D01*
X221335Y-371468D01*
X221339D01*
X221435Y-371498D01*
X221531Y-371520D01*
X221627Y-371539D01*
X221716Y-371550D01*
X221757Y-371553D01*
X221794Y-371557D01*
X221827D01*
X221853Y-371561D01*
X221875D01*
X221894D01*
X221905D01*
X221908D01*
X222005Y-371557D01*
X222093Y-371550D01*
X222175Y-371535D01*
X222249Y-371520D01*
X222312Y-371509D01*
X222338Y-371502D01*
X222360Y-371494D01*
X222378Y-371491D01*
X222389Y-371487D01*
X222397Y-371483D01*
X222400D01*
X222486Y-371446D01*
X222563Y-371406D01*
X222626Y-371361D01*
X222682Y-371313D01*
X222726Y-371272D01*
X222756Y-371239D01*
X222774Y-371213D01*
X222782Y-371209D01*
Y-371206D01*
X222830Y-371128D01*
X222867Y-371043D01*
X222892Y-370961D01*
X222907Y-370884D01*
X222918Y-370813D01*
X222922Y-370784D01*
Y-370758D01*
X222926Y-370740D01*
Y-370710D01*
X222922Y-370617D01*
X222907Y-370532D01*
X222885Y-370462D01*
X222863Y-370399D01*
X222837Y-370351D01*
X222819Y-370314D01*
X222804Y-370292D01*
X222796Y-370284D01*
X222741Y-370225D01*
X222678Y-370170D01*
X222611Y-370125D01*
X222545Y-370088D01*
X222486Y-370059D01*
X222456Y-370048D01*
X222434Y-370040D01*
X222415Y-370033D01*
X222400Y-370025D01*
X222393Y-370022D01*
X222389D01*
X222467Y-369689D01*
X222534Y-369711D01*
X222593Y-369733D01*
X222648Y-369763D01*
X222704Y-369789D01*
X222752Y-369818D01*
X222796Y-369851D01*
X222841Y-369881D01*
X222878Y-369911D01*
X222907Y-369940D01*
X222937Y-369966D01*
X222963Y-369992D01*
X222981Y-370011D01*
X223000Y-370029D01*
X223011Y-370044D01*
X223015Y-370051D01*
X223018Y-370055D01*
X223052Y-370107D01*
X223085Y-370159D01*
X223111Y-370210D01*
X223133Y-370266D01*
X223166Y-370377D01*
X223188Y-370477D01*
X223200Y-370525D01*
X223203Y-370566D01*
X223207Y-370606D01*
X223211Y-370640D01*
X223214Y-370666D01*
Y-370703D01*
X223207Y-370825D01*
X223188Y-370943D01*
X223166Y-371047D01*
X223151Y-371095D01*
X223137Y-371139D01*
X223122Y-371180D01*
X223107Y-371217D01*
X223096Y-371246D01*
X223085Y-371276D01*
X223074Y-371294D01*
X223066Y-371309D01*
X223063Y-371320D01*
X223059Y-371324D01*
X222996Y-371424D01*
X222922Y-371509D01*
X222848Y-371583D01*
X222774Y-371646D01*
X222708Y-371694D01*
X222678Y-371713D01*
X222652Y-371727D01*
X222634Y-371742D01*
X222619Y-371750D01*
X222608Y-371753D01*
X222604Y-371757D01*
X222489Y-371809D01*
X222371Y-371846D01*
X222252Y-371872D01*
X222145Y-371890D01*
X222097Y-371898D01*
X222049Y-371901D01*
X222012Y-371905D01*
X221975D01*
X221949Y-371909D01*
X221927D01*
X221912D01*
X221908D01*
X221775Y-371901D01*
X221646Y-371886D01*
X221531Y-371868D01*
X221476Y-371853D01*
X221427Y-371842D01*
X221383Y-371831D01*
X221342Y-371816D01*
X221305Y-371805D01*
X221276Y-371798D01*
X221253Y-371787D01*
X221235Y-371783D01*
X221224Y-371776D01*
X221220D01*
X221109Y-371720D01*
X221009Y-371657D01*
X220924Y-371590D01*
X220891Y-371557D01*
X220858Y-371528D01*
X220828Y-371498D01*
X220802Y-371468D01*
X220780Y-371443D01*
X220765Y-371420D01*
X220750Y-371406D01*
X220739Y-371391D01*
X220735Y-371383D01*
X220732Y-371380D01*
X220702Y-371328D01*
X220676Y-371276D01*
X220636Y-371165D01*
X220606Y-371054D01*
X220587Y-370947D01*
X220580Y-370895D01*
X220573Y-370850D01*
X220569Y-370810D01*
Y-370777D01*
X220565Y-370747D01*
Y-370706D01*
X220569Y-370632D01*
X220576Y-370562D01*
X220584Y-370495D01*
X220599Y-370432D01*
X220617Y-370373D01*
X220636Y-370318D01*
X220654Y-370266D01*
X220676Y-370218D01*
X220695Y-370177D01*
X220713Y-370136D01*
X220732Y-370107D01*
X220750Y-370077D01*
X220765Y-370059D01*
X220772Y-370040D01*
X220780Y-370033D01*
X220784Y-370029D01*
X220828Y-369977D01*
X220872Y-369933D01*
X220924Y-369892D01*
X220976Y-369851D01*
X221080Y-369785D01*
X221183Y-369733D01*
X221231Y-369711D01*
X221276Y-369692D01*
X221316Y-369678D01*
X221350Y-369667D01*
X221379Y-369655D01*
X221402Y-369648D01*
X221416Y-369644D01*
X221420D01*
X221505Y-369985D01*
D02*
G37*
G36*
X236724Y-365691D02*
X236801Y-365706D01*
X236872Y-365728D01*
X236931Y-365750D01*
X236979Y-365772D01*
X237016Y-365794D01*
X237038Y-365809D01*
X237042Y-365813D01*
X237046D01*
X237105Y-365865D01*
X237157Y-365920D01*
X237197Y-365980D01*
X237234Y-366035D01*
X237260Y-366087D01*
X237279Y-366131D01*
X237286Y-366146D01*
X237290Y-366157D01*
X237293Y-366164D01*
Y-366168D01*
X237323Y-366102D01*
X237356Y-366046D01*
X237390Y-365998D01*
X237423Y-365957D01*
X237453Y-365928D01*
X237475Y-365905D01*
X237490Y-365891D01*
X237497Y-365887D01*
X237549Y-365854D01*
X237600Y-365831D01*
X237652Y-365813D01*
X237704Y-365802D01*
X237745Y-365794D01*
X237778Y-365791D01*
X237800D01*
X237804D01*
X237808D01*
X237860Y-365794D01*
X237908Y-365798D01*
X238000Y-365824D01*
X238082Y-365857D01*
X238152Y-365894D01*
X238207Y-365931D01*
X238229Y-365950D01*
X238252Y-365965D01*
X238266Y-365980D01*
X238278Y-365991D01*
X238281Y-365994D01*
X238285Y-365998D01*
X238318Y-366039D01*
X238352Y-366079D01*
X238377Y-366124D01*
X238400Y-366168D01*
X238433Y-366257D01*
X238455Y-366346D01*
X238466Y-366383D01*
X238470Y-366420D01*
X238474Y-366453D01*
X238477Y-366483D01*
X238481Y-366505D01*
Y-366538D01*
X238477Y-366597D01*
X238474Y-366657D01*
X238452Y-366760D01*
X238437Y-366808D01*
X238422Y-366853D01*
X238403Y-366893D01*
X238385Y-366930D01*
X238366Y-366960D01*
X238348Y-366990D01*
X238333Y-367016D01*
X238318Y-367034D01*
X238307Y-367049D01*
X238296Y-367060D01*
X238292Y-367067D01*
X238289Y-367071D01*
X238252Y-367104D01*
X238215Y-367138D01*
X238174Y-367163D01*
X238133Y-367186D01*
X238056Y-367223D01*
X237982Y-367245D01*
X237919Y-367260D01*
X237889Y-367263D01*
X237867Y-367267D01*
X237845Y-367271D01*
X237830D01*
X237823D01*
X237819D01*
X237752Y-367267D01*
X237689Y-367256D01*
X237634Y-367241D01*
X237586Y-367223D01*
X237549Y-367208D01*
X237519Y-367193D01*
X237504Y-367182D01*
X237497Y-367178D01*
X237453Y-367138D01*
X237412Y-367093D01*
X237375Y-367045D01*
X237345Y-366997D01*
X237323Y-366953D01*
X237308Y-366919D01*
X237301Y-366904D01*
X237297Y-366893D01*
X237293Y-366890D01*
Y-366886D01*
X237267Y-366971D01*
X237234Y-367041D01*
X237193Y-367104D01*
X237157Y-367156D01*
X237120Y-367197D01*
X237090Y-367226D01*
X237071Y-367241D01*
X237068Y-367249D01*
X237064D01*
X236997Y-367289D01*
X236927Y-367323D01*
X236860Y-367345D01*
X236794Y-367360D01*
X236735Y-367367D01*
X236709Y-367371D01*
X236687D01*
X236672Y-367374D01*
X236657D01*
X236650D01*
X236646D01*
X236587Y-367371D01*
X236527Y-367363D01*
X236472Y-367352D01*
X236417Y-367337D01*
X236324Y-367300D01*
X236280Y-367282D01*
X236243Y-367260D01*
X236206Y-367237D01*
X236176Y-367219D01*
X236150Y-367197D01*
X236128Y-367182D01*
X236109Y-367167D01*
X236098Y-367156D01*
X236091Y-367149D01*
X236087Y-367145D01*
X236047Y-367101D01*
X236013Y-367053D01*
X235984Y-367001D01*
X235958Y-366949D01*
X235939Y-366901D01*
X235921Y-366849D01*
X235895Y-366749D01*
X235884Y-366705D01*
X235876Y-366664D01*
X235873Y-366627D01*
X235869Y-366594D01*
X235865Y-366568D01*
Y-366531D01*
X235869Y-366460D01*
X235876Y-366398D01*
X235887Y-366335D01*
X235898Y-366276D01*
X235917Y-366224D01*
X235935Y-366172D01*
X235954Y-366124D01*
X235976Y-366083D01*
X235998Y-366046D01*
X236017Y-366013D01*
X236035Y-365987D01*
X236054Y-365961D01*
X236065Y-365943D01*
X236076Y-365931D01*
X236084Y-365924D01*
X236087Y-365920D01*
X236132Y-365880D01*
X236176Y-365843D01*
X236220Y-365813D01*
X236268Y-365787D01*
X236313Y-365761D01*
X236361Y-365743D01*
X236446Y-365717D01*
X236487Y-365706D01*
X236524Y-365698D01*
X236557Y-365695D01*
X236583Y-365691D01*
X236605Y-365687D01*
X236624D01*
X236635D01*
X236638D01*
X236724Y-365691D01*
D02*
G37*
G36*
X236812Y-368040D02*
X238470D01*
Y-368296D01*
X236812Y-369469D01*
X236524D01*
Y-368355D01*
X235910D01*
Y-368040D01*
X236524D01*
Y-367693D01*
X236812D01*
Y-368040D01*
D02*
G37*
G36*
X236805Y-369990D02*
X236746Y-370005D01*
X236690Y-370024D01*
X236638Y-370042D01*
X236590Y-370061D01*
X236546Y-370083D01*
X236509Y-370105D01*
X236472Y-370131D01*
X236439Y-370153D01*
X236409Y-370172D01*
X236387Y-370194D01*
X236365Y-370212D01*
X236346Y-370227D01*
X236335Y-370242D01*
X236324Y-370253D01*
X236320Y-370257D01*
X236317Y-370260D01*
X236287Y-370297D01*
X236265Y-370338D01*
X236224Y-370420D01*
X236194Y-370497D01*
X236176Y-370575D01*
X236161Y-370641D01*
X236157Y-370667D01*
Y-370693D01*
X236154Y-370715D01*
Y-370741D01*
X236157Y-370827D01*
X236172Y-370908D01*
X236191Y-370982D01*
X236213Y-371048D01*
X236235Y-371100D01*
X236246Y-371123D01*
X236254Y-371141D01*
X236261Y-371156D01*
X236268Y-371167D01*
X236272Y-371174D01*
Y-371178D01*
X236324Y-371248D01*
X236380Y-371307D01*
X236442Y-371359D01*
X236502Y-371400D01*
X236553Y-371433D01*
X236598Y-371456D01*
X236616Y-371463D01*
X236627Y-371470D01*
X236635Y-371474D01*
X236638D01*
X236735Y-371504D01*
X236831Y-371526D01*
X236927Y-371544D01*
X237016Y-371555D01*
X237057Y-371559D01*
X237094Y-371563D01*
X237127D01*
X237153Y-371567D01*
X237175D01*
X237193D01*
X237205D01*
X237208D01*
X237304Y-371563D01*
X237393Y-371555D01*
X237475Y-371541D01*
X237549Y-371526D01*
X237612Y-371515D01*
X237637Y-371507D01*
X237660Y-371500D01*
X237678Y-371496D01*
X237689Y-371493D01*
X237697Y-371489D01*
X237700D01*
X237786Y-371452D01*
X237863Y-371411D01*
X237926Y-371367D01*
X237982Y-371319D01*
X238026Y-371278D01*
X238056Y-371245D01*
X238074Y-371219D01*
X238082Y-371215D01*
Y-371211D01*
X238130Y-371134D01*
X238167Y-371048D01*
X238193Y-370967D01*
X238207Y-370889D01*
X238218Y-370819D01*
X238222Y-370790D01*
Y-370764D01*
X238226Y-370745D01*
Y-370715D01*
X238222Y-370623D01*
X238207Y-370538D01*
X238185Y-370468D01*
X238163Y-370405D01*
X238137Y-370357D01*
X238119Y-370320D01*
X238104Y-370297D01*
X238096Y-370290D01*
X238041Y-370231D01*
X237978Y-370175D01*
X237911Y-370131D01*
X237845Y-370094D01*
X237786Y-370064D01*
X237756Y-370053D01*
X237734Y-370046D01*
X237715Y-370038D01*
X237700Y-370031D01*
X237693Y-370027D01*
X237689D01*
X237767Y-369694D01*
X237834Y-369717D01*
X237893Y-369739D01*
X237948Y-369768D01*
X238004Y-369794D01*
X238052Y-369824D01*
X238096Y-369857D01*
X238141Y-369887D01*
X238178Y-369916D01*
X238207Y-369946D01*
X238237Y-369972D01*
X238263Y-369998D01*
X238281Y-370016D01*
X238300Y-370035D01*
X238311Y-370050D01*
X238315Y-370057D01*
X238318Y-370061D01*
X238352Y-370112D01*
X238385Y-370164D01*
X238411Y-370216D01*
X238433Y-370271D01*
X238466Y-370382D01*
X238489Y-370482D01*
X238500Y-370531D01*
X238503Y-370571D01*
X238507Y-370612D01*
X238511Y-370645D01*
X238514Y-370671D01*
Y-370708D01*
X238507Y-370830D01*
X238489Y-370949D01*
X238466Y-371052D01*
X238452Y-371100D01*
X238437Y-371145D01*
X238422Y-371185D01*
X238407Y-371222D01*
X238396Y-371252D01*
X238385Y-371282D01*
X238374Y-371300D01*
X238366Y-371315D01*
X238363Y-371326D01*
X238359Y-371330D01*
X238296Y-371430D01*
X238222Y-371515D01*
X238148Y-371589D01*
X238074Y-371652D01*
X238007Y-371700D01*
X237978Y-371718D01*
X237952Y-371733D01*
X237933Y-371748D01*
X237919Y-371755D01*
X237908Y-371759D01*
X237904Y-371763D01*
X237789Y-371814D01*
X237671Y-371851D01*
X237552Y-371877D01*
X237445Y-371896D01*
X237397Y-371903D01*
X237349Y-371907D01*
X237312Y-371911D01*
X237275D01*
X237249Y-371914D01*
X237227D01*
X237212D01*
X237208D01*
X237075Y-371907D01*
X236946Y-371892D01*
X236831Y-371874D01*
X236775Y-371859D01*
X236727Y-371848D01*
X236683Y-371837D01*
X236642Y-371822D01*
X236605Y-371811D01*
X236576Y-371803D01*
X236553Y-371792D01*
X236535Y-371789D01*
X236524Y-371781D01*
X236520D01*
X236409Y-371726D01*
X236309Y-371663D01*
X236224Y-371596D01*
X236191Y-371563D01*
X236157Y-371533D01*
X236128Y-371504D01*
X236102Y-371474D01*
X236080Y-371448D01*
X236065Y-371426D01*
X236050Y-371411D01*
X236039Y-371396D01*
X236035Y-371389D01*
X236032Y-371385D01*
X236002Y-371333D01*
X235976Y-371282D01*
X235935Y-371171D01*
X235906Y-371060D01*
X235887Y-370952D01*
X235880Y-370901D01*
X235873Y-370856D01*
X235869Y-370815D01*
Y-370782D01*
X235865Y-370753D01*
Y-370712D01*
X235869Y-370638D01*
X235876Y-370567D01*
X235884Y-370501D01*
X235898Y-370438D01*
X235917Y-370379D01*
X235935Y-370323D01*
X235954Y-370271D01*
X235976Y-370223D01*
X235995Y-370183D01*
X236013Y-370142D01*
X236032Y-370112D01*
X236050Y-370083D01*
X236065Y-370064D01*
X236072Y-370046D01*
X236080Y-370038D01*
X236084Y-370035D01*
X236128Y-369983D01*
X236172Y-369938D01*
X236224Y-369898D01*
X236276Y-369857D01*
X236380Y-369791D01*
X236483Y-369739D01*
X236531Y-369717D01*
X236576Y-369698D01*
X236616Y-369683D01*
X236650Y-369672D01*
X236679Y-369661D01*
X236701Y-369654D01*
X236716Y-369650D01*
X236720D01*
X236805Y-369990D01*
D02*
G37*
G36*
X241408Y-365691D02*
X241482Y-365698D01*
X241552Y-365706D01*
X241615Y-365713D01*
X241674Y-365721D01*
X241730Y-365732D01*
X241778Y-365743D01*
X241819Y-365754D01*
X241856Y-365761D01*
X241889Y-365772D01*
X241915Y-365780D01*
X241933Y-365787D01*
X241948Y-365794D01*
X241956Y-365798D01*
X241959D01*
X242048Y-365843D01*
X242126Y-365891D01*
X242193Y-365946D01*
X242248Y-365994D01*
X242289Y-366042D01*
X242318Y-366079D01*
X242329Y-366094D01*
X242337Y-366105D01*
X242344Y-366109D01*
Y-366113D01*
X242389Y-366190D01*
X242422Y-366268D01*
X242448Y-366346D01*
X242463Y-366416D01*
X242474Y-366479D01*
X242477Y-366505D01*
Y-366523D01*
X242481Y-366542D01*
Y-366568D01*
X242477Y-366631D01*
X242470Y-366690D01*
X242459Y-366749D01*
X242444Y-366801D01*
X242403Y-366901D01*
X242385Y-366945D01*
X242363Y-366982D01*
X242337Y-367019D01*
X242318Y-367049D01*
X242296Y-367078D01*
X242278Y-367101D01*
X242263Y-367119D01*
X242252Y-367130D01*
X242244Y-367138D01*
X242241Y-367141D01*
X242196Y-367182D01*
X242144Y-367215D01*
X242096Y-367249D01*
X242044Y-367274D01*
X241989Y-367297D01*
X241937Y-367315D01*
X241841Y-367341D01*
X241793Y-367352D01*
X241752Y-367360D01*
X241711Y-367363D01*
X241678Y-367367D01*
X241652Y-367371D01*
X241634D01*
X241619D01*
X241615D01*
X241545Y-367367D01*
X241482Y-367360D01*
X241419Y-367352D01*
X241360Y-367337D01*
X241308Y-367319D01*
X241256Y-367300D01*
X241212Y-367282D01*
X241171Y-367260D01*
X241134Y-367241D01*
X241101Y-367223D01*
X241075Y-367204D01*
X241049Y-367186D01*
X241031Y-367171D01*
X241020Y-367163D01*
X241012Y-367156D01*
X241008Y-367152D01*
X240968Y-367112D01*
X240934Y-367067D01*
X240901Y-367023D01*
X240875Y-366975D01*
X240853Y-366930D01*
X240835Y-366886D01*
X240809Y-366801D01*
X240798Y-366764D01*
X240790Y-366727D01*
X240787Y-366697D01*
X240783Y-366668D01*
X240779Y-366646D01*
Y-366616D01*
X240783Y-366546D01*
X240794Y-366479D01*
X240809Y-366420D01*
X240827Y-366364D01*
X240842Y-366324D01*
X240857Y-366290D01*
X240868Y-366268D01*
X240872Y-366261D01*
X240909Y-366201D01*
X240949Y-366150D01*
X240990Y-366105D01*
X241027Y-366068D01*
X241064Y-366042D01*
X241090Y-366020D01*
X241108Y-366005D01*
X241116Y-366002D01*
X241086D01*
X241068D01*
X241057D01*
X241053D01*
X240979Y-366005D01*
X240909Y-366009D01*
X240846Y-366017D01*
X240787Y-366024D01*
X240738Y-366035D01*
X240701Y-366042D01*
X240687Y-366046D01*
X240675D01*
X240672Y-366050D01*
X240668D01*
X240601Y-366068D01*
X240542Y-366087D01*
X240491Y-366105D01*
X240446Y-366124D01*
X240413Y-366139D01*
X240387Y-366153D01*
X240368Y-366161D01*
X240365Y-366164D01*
X240324Y-366194D01*
X240291Y-366224D01*
X240261Y-366253D01*
X240235Y-366283D01*
X240213Y-366305D01*
X240198Y-366327D01*
X240191Y-366342D01*
X240187Y-366346D01*
X240165Y-366387D01*
X240150Y-366431D01*
X240139Y-366472D01*
X240132Y-366512D01*
X240128Y-366546D01*
X240124Y-366571D01*
Y-366597D01*
X240128Y-366657D01*
X240139Y-366712D01*
X240154Y-366760D01*
X240172Y-366801D01*
X240187Y-366830D01*
X240202Y-366856D01*
X240213Y-366871D01*
X240217Y-366875D01*
X240257Y-366912D01*
X240305Y-366941D01*
X240357Y-366967D01*
X240409Y-366986D01*
X240454Y-367001D01*
X240494Y-367012D01*
X240509Y-367016D01*
X240516D01*
X240524Y-367019D01*
X240528D01*
X240502Y-367323D01*
X240394Y-367300D01*
X240302Y-367271D01*
X240220Y-367234D01*
X240154Y-367197D01*
X240102Y-367160D01*
X240080Y-367141D01*
X240061Y-367126D01*
X240050Y-367115D01*
X240039Y-367104D01*
X240035Y-367101D01*
X240032Y-367097D01*
X240002Y-367060D01*
X239976Y-367019D01*
X239935Y-366938D01*
X239906Y-366856D01*
X239887Y-366779D01*
X239873Y-366708D01*
X239869Y-366679D01*
Y-366653D01*
X239865Y-366634D01*
Y-366605D01*
X239873Y-366501D01*
X239887Y-366409D01*
X239913Y-366324D01*
X239943Y-366253D01*
X239954Y-366224D01*
X239969Y-366194D01*
X239984Y-366172D01*
X239995Y-366150D01*
X240002Y-366135D01*
X240009Y-366124D01*
X240017Y-366116D01*
Y-366113D01*
X240080Y-366039D01*
X240150Y-365972D01*
X240224Y-365920D01*
X240294Y-365876D01*
X240357Y-365839D01*
X240387Y-365824D01*
X240409Y-365813D01*
X240431Y-365806D01*
X240446Y-365798D01*
X240454Y-365794D01*
X240457D01*
X240513Y-365776D01*
X240576Y-365757D01*
X240701Y-365732D01*
X240835Y-365713D01*
X240960Y-365702D01*
X241016Y-365695D01*
X241071Y-365691D01*
X241120D01*
X241160Y-365687D01*
X241194D01*
X241219D01*
X241238D01*
X241242D01*
X241327D01*
X241408Y-365691D01*
D02*
G37*
G36*
X240812Y-368040D02*
X242470D01*
Y-368296D01*
X240812Y-369469D01*
X240524D01*
Y-368355D01*
X239910D01*
Y-368040D01*
X240524D01*
Y-367693D01*
X240812D01*
Y-368040D01*
D02*
G37*
G36*
X240805Y-369990D02*
X240746Y-370005D01*
X240690Y-370024D01*
X240638Y-370042D01*
X240590Y-370061D01*
X240546Y-370083D01*
X240509Y-370105D01*
X240472Y-370131D01*
X240439Y-370153D01*
X240409Y-370172D01*
X240387Y-370194D01*
X240365Y-370212D01*
X240346Y-370227D01*
X240335Y-370242D01*
X240324Y-370253D01*
X240320Y-370257D01*
X240317Y-370260D01*
X240287Y-370297D01*
X240265Y-370338D01*
X240224Y-370420D01*
X240195Y-370497D01*
X240176Y-370575D01*
X240161Y-370641D01*
X240158Y-370667D01*
Y-370693D01*
X240154Y-370715D01*
Y-370741D01*
X240158Y-370827D01*
X240172Y-370908D01*
X240191Y-370982D01*
X240213Y-371048D01*
X240235Y-371100D01*
X240246Y-371123D01*
X240254Y-371141D01*
X240261Y-371156D01*
X240268Y-371167D01*
X240272Y-371174D01*
Y-371178D01*
X240324Y-371248D01*
X240380Y-371307D01*
X240442Y-371359D01*
X240502Y-371400D01*
X240553Y-371433D01*
X240598Y-371456D01*
X240616Y-371463D01*
X240627Y-371470D01*
X240635Y-371474D01*
X240638D01*
X240735Y-371504D01*
X240831Y-371526D01*
X240927Y-371544D01*
X241016Y-371555D01*
X241057Y-371559D01*
X241094Y-371563D01*
X241127D01*
X241153Y-371567D01*
X241175D01*
X241194D01*
X241205D01*
X241208D01*
X241304Y-371563D01*
X241393Y-371555D01*
X241475Y-371541D01*
X241549Y-371526D01*
X241612Y-371515D01*
X241637Y-371507D01*
X241660Y-371500D01*
X241678Y-371496D01*
X241689Y-371493D01*
X241697Y-371489D01*
X241700D01*
X241786Y-371452D01*
X241863Y-371411D01*
X241926Y-371367D01*
X241982Y-371319D01*
X242026Y-371278D01*
X242056Y-371245D01*
X242074Y-371219D01*
X242081Y-371215D01*
Y-371211D01*
X242130Y-371134D01*
X242167Y-371048D01*
X242193Y-370967D01*
X242207Y-370889D01*
X242218Y-370819D01*
X242222Y-370790D01*
Y-370764D01*
X242226Y-370745D01*
Y-370715D01*
X242222Y-370623D01*
X242207Y-370538D01*
X242185Y-370468D01*
X242163Y-370405D01*
X242137Y-370357D01*
X242119Y-370320D01*
X242104Y-370297D01*
X242096Y-370290D01*
X242041Y-370231D01*
X241978Y-370175D01*
X241911Y-370131D01*
X241845Y-370094D01*
X241786Y-370064D01*
X241756Y-370053D01*
X241734Y-370046D01*
X241715Y-370038D01*
X241700Y-370031D01*
X241693Y-370027D01*
X241689D01*
X241767Y-369694D01*
X241834Y-369717D01*
X241893Y-369739D01*
X241948Y-369768D01*
X242004Y-369794D01*
X242052Y-369824D01*
X242096Y-369857D01*
X242141Y-369887D01*
X242178Y-369916D01*
X242207Y-369946D01*
X242237Y-369972D01*
X242263Y-369998D01*
X242281Y-370016D01*
X242300Y-370035D01*
X242311Y-370050D01*
X242315Y-370057D01*
X242318Y-370061D01*
X242352Y-370112D01*
X242385Y-370164D01*
X242411Y-370216D01*
X242433Y-370271D01*
X242466Y-370382D01*
X242489Y-370482D01*
X242500Y-370531D01*
X242503Y-370571D01*
X242507Y-370612D01*
X242511Y-370645D01*
X242514Y-370671D01*
Y-370708D01*
X242507Y-370830D01*
X242489Y-370949D01*
X242466Y-371052D01*
X242452Y-371100D01*
X242437Y-371145D01*
X242422Y-371185D01*
X242407Y-371222D01*
X242396Y-371252D01*
X242385Y-371282D01*
X242374Y-371300D01*
X242366Y-371315D01*
X242363Y-371326D01*
X242359Y-371330D01*
X242296Y-371430D01*
X242222Y-371515D01*
X242148Y-371589D01*
X242074Y-371652D01*
X242007Y-371700D01*
X241978Y-371718D01*
X241952Y-371733D01*
X241933Y-371748D01*
X241919Y-371755D01*
X241908Y-371759D01*
X241904Y-371763D01*
X241789Y-371814D01*
X241671Y-371851D01*
X241552Y-371877D01*
X241445Y-371896D01*
X241397Y-371903D01*
X241349Y-371907D01*
X241312Y-371911D01*
X241275D01*
X241249Y-371914D01*
X241227D01*
X241212D01*
X241208D01*
X241075Y-371907D01*
X240946Y-371892D01*
X240831Y-371874D01*
X240775Y-371859D01*
X240727Y-371848D01*
X240683Y-371837D01*
X240642Y-371822D01*
X240605Y-371811D01*
X240576Y-371803D01*
X240553Y-371792D01*
X240535Y-371789D01*
X240524Y-371781D01*
X240520D01*
X240409Y-371726D01*
X240309Y-371663D01*
X240224Y-371596D01*
X240191Y-371563D01*
X240158Y-371533D01*
X240128Y-371504D01*
X240102Y-371474D01*
X240080Y-371448D01*
X240065Y-371426D01*
X240050Y-371411D01*
X240039Y-371396D01*
X240035Y-371389D01*
X240032Y-371385D01*
X240002Y-371333D01*
X239976Y-371282D01*
X239935Y-371171D01*
X239906Y-371060D01*
X239887Y-370952D01*
X239880Y-370901D01*
X239873Y-370856D01*
X239869Y-370815D01*
Y-370782D01*
X239865Y-370753D01*
Y-370712D01*
X239869Y-370638D01*
X239876Y-370567D01*
X239884Y-370501D01*
X239898Y-370438D01*
X239917Y-370379D01*
X239935Y-370323D01*
X239954Y-370271D01*
X239976Y-370223D01*
X239995Y-370183D01*
X240013Y-370142D01*
X240032Y-370112D01*
X240050Y-370083D01*
X240065Y-370064D01*
X240072Y-370046D01*
X240080Y-370038D01*
X240084Y-370035D01*
X240128Y-369983D01*
X240172Y-369938D01*
X240224Y-369898D01*
X240276Y-369857D01*
X240380Y-369791D01*
X240483Y-369739D01*
X240531Y-369717D01*
X240576Y-369698D01*
X240616Y-369683D01*
X240650Y-369672D01*
X240679Y-369661D01*
X240701Y-369654D01*
X240716Y-369650D01*
X240720D01*
X240805Y-369990D01*
D02*
G37*
G36*
X252808Y-365685D02*
X252868D01*
X252927Y-365689D01*
X252978Y-365696D01*
X253030Y-365700D01*
X253075Y-365704D01*
X253115Y-365711D01*
X253152Y-365715D01*
X253186Y-365722D01*
X253211Y-365726D01*
X253234Y-365730D01*
X253252Y-365733D01*
X253263Y-365737D01*
X253271Y-365741D01*
X253274D01*
X253356Y-365763D01*
X253430Y-365789D01*
X253493Y-365819D01*
X253548Y-365841D01*
X253596Y-365867D01*
X253630Y-365881D01*
X253648Y-365896D01*
X253656Y-365900D01*
X253711Y-365941D01*
X253759Y-365981D01*
X253800Y-366026D01*
X253837Y-366066D01*
X253863Y-366103D01*
X253881Y-366133D01*
X253892Y-366151D01*
X253896Y-366155D01*
Y-366159D01*
X253926Y-366218D01*
X253944Y-366281D01*
X253959Y-366340D01*
X253970Y-366396D01*
X253977Y-366444D01*
X253981Y-366484D01*
Y-366518D01*
X253974Y-366618D01*
X253959Y-366710D01*
X253933Y-366788D01*
X253907Y-366855D01*
X253878Y-366910D01*
X253866Y-366932D01*
X253852Y-366951D01*
X253844Y-366966D01*
X253837Y-366977D01*
X253829Y-366980D01*
Y-366984D01*
X253770Y-367051D01*
X253700Y-367106D01*
X253630Y-367154D01*
X253563Y-367191D01*
X253500Y-367221D01*
X253474Y-367236D01*
X253448Y-367243D01*
X253430Y-367250D01*
X253415Y-367258D01*
X253408Y-367262D01*
X253404D01*
X253348Y-367276D01*
X253293Y-367291D01*
X253171Y-367313D01*
X253049Y-367332D01*
X252934Y-367343D01*
X252878Y-367347D01*
X252831Y-367350D01*
X252786D01*
X252745Y-367354D01*
X252716D01*
X252690D01*
X252675D01*
X252671D01*
X252542Y-367350D01*
X252420Y-367343D01*
X252309Y-367332D01*
X252205Y-367313D01*
X252109Y-367295D01*
X252024Y-367273D01*
X251946Y-367250D01*
X251880Y-367228D01*
X251820Y-367206D01*
X251769Y-367180D01*
X251724Y-367162D01*
X251691Y-367143D01*
X251661Y-367125D01*
X251643Y-367113D01*
X251632Y-367106D01*
X251628Y-367102D01*
X251584Y-367062D01*
X251543Y-367017D01*
X251506Y-366969D01*
X251476Y-366921D01*
X251450Y-366873D01*
X251428Y-366825D01*
X251413Y-366777D01*
X251398Y-366732D01*
X251387Y-366688D01*
X251380Y-366647D01*
X251373Y-366610D01*
X251369Y-366581D01*
X251365Y-366555D01*
Y-366518D01*
X251373Y-366418D01*
X251387Y-366325D01*
X251413Y-366248D01*
X251439Y-366181D01*
X251465Y-366126D01*
X251480Y-366107D01*
X251491Y-366089D01*
X251499Y-366074D01*
X251506Y-366063D01*
X251513Y-366059D01*
Y-366055D01*
X251576Y-365989D01*
X251643Y-365933D01*
X251717Y-365885D01*
X251783Y-365848D01*
X251846Y-365819D01*
X251872Y-365804D01*
X251898Y-365796D01*
X251917Y-365789D01*
X251931Y-365781D01*
X251939Y-365778D01*
X251942D01*
X251998Y-365759D01*
X252053Y-365744D01*
X252172Y-365722D01*
X252294Y-365704D01*
X252412Y-365693D01*
X252464Y-365689D01*
X252512Y-365685D01*
X252557D01*
X252597Y-365682D01*
X252627D01*
X252653D01*
X252668D01*
X252671D01*
X252742D01*
X252808Y-365685D01*
D02*
G37*
G36*
X252342Y-367650D02*
X252405Y-367657D01*
X252468Y-367669D01*
X252523Y-367683D01*
X252575Y-367702D01*
X252627Y-367720D01*
X252671Y-367742D01*
X252712Y-367761D01*
X252749Y-367783D01*
X252782Y-367805D01*
X252808Y-367824D01*
X252834Y-367842D01*
X252853Y-367857D01*
X252864Y-367868D01*
X252871Y-367876D01*
X252875Y-367879D01*
X252916Y-367924D01*
X252953Y-367968D01*
X252982Y-368016D01*
X253008Y-368064D01*
X253034Y-368112D01*
X253052Y-368161D01*
X253078Y-368249D01*
X253089Y-368290D01*
X253097Y-368327D01*
X253101Y-368360D01*
X253104Y-368390D01*
X253108Y-368412D01*
Y-368494D01*
X253101Y-368538D01*
X253082Y-368627D01*
X253056Y-368708D01*
X253027Y-368782D01*
X252997Y-368841D01*
X252982Y-368867D01*
X252971Y-368889D01*
X252960Y-368908D01*
X252953Y-368919D01*
X252949Y-368927D01*
X252945Y-368930D01*
X253637Y-368793D01*
Y-367768D01*
X253937D01*
Y-369041D01*
X252620Y-369289D01*
X252579Y-368993D01*
X252620Y-368967D01*
X252653Y-368934D01*
X252686Y-368904D01*
X252712Y-368875D01*
X252730Y-368845D01*
X252749Y-368823D01*
X252756Y-368808D01*
X252760Y-368804D01*
X252782Y-368756D01*
X252801Y-368708D01*
X252812Y-368664D01*
X252823Y-368619D01*
X252827Y-368582D01*
X252831Y-368553D01*
Y-368482D01*
X252823Y-368438D01*
X252805Y-368360D01*
X252779Y-368294D01*
X252753Y-368235D01*
X252723Y-368190D01*
X252697Y-368157D01*
X252679Y-368138D01*
X252675Y-368131D01*
X252671D01*
X252608Y-368079D01*
X252542Y-368042D01*
X252471Y-368016D01*
X252401Y-367998D01*
X252342Y-367987D01*
X252316Y-367983D01*
X252294D01*
X252275Y-367979D01*
X252261D01*
X252253D01*
X252250D01*
X252198D01*
X252150Y-367987D01*
X252057Y-368005D01*
X251979Y-368031D01*
X251917Y-368057D01*
X251865Y-368087D01*
X251824Y-368112D01*
X251813Y-368124D01*
X251802Y-368131D01*
X251798Y-368135D01*
X251795Y-368138D01*
X251765Y-368168D01*
X251739Y-368198D01*
X251694Y-368264D01*
X251665Y-368327D01*
X251646Y-368390D01*
X251632Y-368442D01*
X251628Y-368486D01*
X251624Y-368501D01*
Y-368523D01*
X251628Y-368594D01*
X251643Y-368656D01*
X251661Y-368712D01*
X251683Y-368756D01*
X251706Y-368797D01*
X251724Y-368827D01*
X251739Y-368841D01*
X251743Y-368849D01*
X251795Y-368893D01*
X251850Y-368930D01*
X251913Y-368960D01*
X251968Y-368982D01*
X252024Y-368997D01*
X252065Y-369008D01*
X252083Y-369012D01*
X252094Y-369015D01*
X252101D01*
X252105D01*
X252079Y-369345D01*
X252020Y-369337D01*
X251965Y-369326D01*
X251861Y-369293D01*
X251772Y-369252D01*
X251732Y-369230D01*
X251698Y-369208D01*
X251665Y-369189D01*
X251635Y-369167D01*
X251613Y-369148D01*
X251595Y-369130D01*
X251580Y-369115D01*
X251565Y-369108D01*
X251561Y-369100D01*
X251558Y-369097D01*
X251524Y-369052D01*
X251495Y-369008D01*
X251469Y-368960D01*
X251447Y-368912D01*
X251413Y-368819D01*
X251391Y-368727D01*
X251380Y-368686D01*
X251376Y-368645D01*
X251373Y-368612D01*
X251369Y-368582D01*
X251365Y-368556D01*
Y-368523D01*
X251369Y-368445D01*
X251380Y-368372D01*
X251395Y-368301D01*
X251413Y-368238D01*
X251439Y-368179D01*
X251465Y-368124D01*
X251491Y-368072D01*
X251521Y-368027D01*
X251550Y-367987D01*
X251576Y-367950D01*
X251606Y-367920D01*
X251628Y-367894D01*
X251646Y-367876D01*
X251661Y-367861D01*
X251672Y-367853D01*
X251676Y-367850D01*
X251724Y-367813D01*
X251776Y-367783D01*
X251824Y-367754D01*
X251876Y-367731D01*
X251976Y-367694D01*
X252072Y-367672D01*
X252113Y-367665D01*
X252153Y-367657D01*
X252187Y-367654D01*
X252216Y-367650D01*
X252242Y-367646D01*
X252261D01*
X252272D01*
X252275D01*
X252342Y-367650D01*
D02*
G37*
G36*
X252305Y-369974D02*
X252246Y-369988D01*
X252190Y-370007D01*
X252138Y-370025D01*
X252091Y-370044D01*
X252046Y-370066D01*
X252009Y-370088D01*
X251972Y-370114D01*
X251939Y-370136D01*
X251909Y-370155D01*
X251887Y-370177D01*
X251865Y-370196D01*
X251846Y-370210D01*
X251835Y-370225D01*
X251824Y-370236D01*
X251820Y-370240D01*
X251817Y-370244D01*
X251787Y-370281D01*
X251765Y-370321D01*
X251724Y-370403D01*
X251694Y-370480D01*
X251676Y-370558D01*
X251661Y-370625D01*
X251658Y-370651D01*
Y-370677D01*
X251654Y-370699D01*
Y-370725D01*
X251658Y-370810D01*
X251672Y-370891D01*
X251691Y-370965D01*
X251713Y-371032D01*
X251735Y-371084D01*
X251746Y-371106D01*
X251754Y-371124D01*
X251761Y-371139D01*
X251769Y-371150D01*
X251772Y-371158D01*
Y-371161D01*
X251824Y-371232D01*
X251880Y-371291D01*
X251942Y-371343D01*
X252002Y-371383D01*
X252053Y-371417D01*
X252098Y-371439D01*
X252116Y-371446D01*
X252127Y-371454D01*
X252135Y-371457D01*
X252138D01*
X252235Y-371487D01*
X252331Y-371509D01*
X252427Y-371528D01*
X252516Y-371539D01*
X252557Y-371542D01*
X252594Y-371546D01*
X252627D01*
X252653Y-371550D01*
X252675D01*
X252694D01*
X252705D01*
X252708D01*
X252805Y-371546D01*
X252893Y-371539D01*
X252975Y-371524D01*
X253049Y-371509D01*
X253112Y-371498D01*
X253138Y-371491D01*
X253160Y-371483D01*
X253178Y-371480D01*
X253189Y-371476D01*
X253197Y-371472D01*
X253201D01*
X253286Y-371435D01*
X253363Y-371394D01*
X253426Y-371350D01*
X253482Y-371302D01*
X253526Y-371261D01*
X253556Y-371228D01*
X253574Y-371202D01*
X253582Y-371198D01*
Y-371195D01*
X253630Y-371117D01*
X253667Y-371032D01*
X253693Y-370950D01*
X253707Y-370873D01*
X253718Y-370802D01*
X253722Y-370773D01*
Y-370747D01*
X253726Y-370728D01*
Y-370699D01*
X253722Y-370606D01*
X253707Y-370521D01*
X253685Y-370451D01*
X253663Y-370388D01*
X253637Y-370340D01*
X253619Y-370303D01*
X253604Y-370281D01*
X253596Y-370273D01*
X253541Y-370214D01*
X253478Y-370159D01*
X253411Y-370114D01*
X253345Y-370077D01*
X253286Y-370048D01*
X253256Y-370037D01*
X253234Y-370029D01*
X253215Y-370022D01*
X253201Y-370014D01*
X253193Y-370011D01*
X253189D01*
X253267Y-369678D01*
X253334Y-369700D01*
X253393Y-369722D01*
X253448Y-369752D01*
X253504Y-369777D01*
X253552Y-369807D01*
X253596Y-369840D01*
X253641Y-369870D01*
X253678Y-369900D01*
X253707Y-369929D01*
X253737Y-369955D01*
X253763Y-369981D01*
X253781Y-370000D01*
X253800Y-370018D01*
X253811Y-370033D01*
X253815Y-370040D01*
X253818Y-370044D01*
X253852Y-370096D01*
X253885Y-370147D01*
X253911Y-370199D01*
X253933Y-370255D01*
X253966Y-370366D01*
X253989Y-370466D01*
X254000Y-370514D01*
X254003Y-370554D01*
X254007Y-370595D01*
X254011Y-370628D01*
X254014Y-370654D01*
Y-370691D01*
X254007Y-370813D01*
X253989Y-370932D01*
X253966Y-371036D01*
X253952Y-371084D01*
X253937Y-371128D01*
X253922Y-371169D01*
X253907Y-371206D01*
X253896Y-371235D01*
X253885Y-371265D01*
X253874Y-371283D01*
X253866Y-371298D01*
X253863Y-371309D01*
X253859Y-371313D01*
X253796Y-371413D01*
X253722Y-371498D01*
X253648Y-371572D01*
X253574Y-371635D01*
X253507Y-371683D01*
X253478Y-371702D01*
X253452Y-371716D01*
X253434Y-371731D01*
X253419Y-371739D01*
X253408Y-371742D01*
X253404Y-371746D01*
X253289Y-371798D01*
X253171Y-371835D01*
X253052Y-371861D01*
X252945Y-371879D01*
X252897Y-371886D01*
X252849Y-371890D01*
X252812Y-371894D01*
X252775D01*
X252749Y-371898D01*
X252727D01*
X252712D01*
X252708D01*
X252575Y-371890D01*
X252446Y-371875D01*
X252331Y-371857D01*
X252275Y-371842D01*
X252227Y-371831D01*
X252183Y-371820D01*
X252142Y-371805D01*
X252105Y-371794D01*
X252076Y-371787D01*
X252053Y-371776D01*
X252035Y-371772D01*
X252024Y-371764D01*
X252020D01*
X251909Y-371709D01*
X251809Y-371646D01*
X251724Y-371579D01*
X251691Y-371546D01*
X251658Y-371516D01*
X251628Y-371487D01*
X251602Y-371457D01*
X251580Y-371431D01*
X251565Y-371409D01*
X251550Y-371394D01*
X251539Y-371380D01*
X251535Y-371372D01*
X251532Y-371369D01*
X251502Y-371317D01*
X251476Y-371265D01*
X251436Y-371154D01*
X251406Y-371043D01*
X251387Y-370936D01*
X251380Y-370884D01*
X251373Y-370839D01*
X251369Y-370799D01*
Y-370765D01*
X251365Y-370736D01*
Y-370695D01*
X251369Y-370621D01*
X251376Y-370551D01*
X251384Y-370484D01*
X251398Y-370421D01*
X251417Y-370362D01*
X251436Y-370307D01*
X251454Y-370255D01*
X251476Y-370207D01*
X251495Y-370166D01*
X251513Y-370125D01*
X251532Y-370096D01*
X251550Y-370066D01*
X251565Y-370048D01*
X251572Y-370029D01*
X251580Y-370022D01*
X251584Y-370018D01*
X251628Y-369966D01*
X251672Y-369922D01*
X251724Y-369881D01*
X251776Y-369840D01*
X251880Y-369774D01*
X251983Y-369722D01*
X252031Y-369700D01*
X252076Y-369681D01*
X252116Y-369667D01*
X252150Y-369655D01*
X252179Y-369644D01*
X252202Y-369637D01*
X252216Y-369633D01*
X252220D01*
X252305Y-369974D01*
D02*
G37*
G36*
X258232Y-377940D02*
X258169Y-377977D01*
X258110Y-378017D01*
X258051Y-378065D01*
X257999Y-378110D01*
X257955Y-378154D01*
X257918Y-378188D01*
X257907Y-378202D01*
X257896Y-378214D01*
X257892Y-378217D01*
X257888Y-378221D01*
X257825Y-378299D01*
X257766Y-378376D01*
X257714Y-378450D01*
X257674Y-378524D01*
X257636Y-378587D01*
X257622Y-378613D01*
X257611Y-378635D01*
X257599Y-378654D01*
X257596Y-378669D01*
X257589Y-378676D01*
Y-378680D01*
X257285D01*
X257307Y-378624D01*
X257333Y-378569D01*
X257359Y-378513D01*
X257385Y-378461D01*
X257407Y-378417D01*
X257426Y-378380D01*
X257440Y-378358D01*
X257444Y-378354D01*
Y-378350D01*
X257485Y-378284D01*
X257526Y-378225D01*
X257563Y-378173D01*
X257596Y-378132D01*
X257622Y-378095D01*
X257644Y-378073D01*
X257659Y-378054D01*
X257662Y-378051D01*
X255661D01*
Y-377736D01*
X258232D01*
Y-377940D01*
D02*
G37*
G36*
X256593Y-379216D02*
X256656Y-379224D01*
X256719Y-379235D01*
X256774Y-379250D01*
X256826Y-379268D01*
X256878Y-379287D01*
X256922Y-379309D01*
X256963Y-379327D01*
X257000Y-379349D01*
X257033Y-379372D01*
X257059Y-379390D01*
X257085Y-379409D01*
X257104Y-379423D01*
X257115Y-379434D01*
X257122Y-379442D01*
X257126Y-379446D01*
X257167Y-379490D01*
X257204Y-379534D01*
X257233Y-379583D01*
X257259Y-379631D01*
X257285Y-379679D01*
X257304Y-379727D01*
X257329Y-379816D01*
X257341Y-379856D01*
X257348Y-379893D01*
X257352Y-379927D01*
X257355Y-379956D01*
X257359Y-379978D01*
Y-380060D01*
X257352Y-380104D01*
X257333Y-380193D01*
X257307Y-380274D01*
X257278Y-380348D01*
X257248Y-380408D01*
X257233Y-380434D01*
X257222Y-380456D01*
X257211Y-380474D01*
X257204Y-380485D01*
X257200Y-380493D01*
X257196Y-380496D01*
X257888Y-380360D01*
Y-379335D01*
X258188D01*
Y-380607D01*
X256871Y-380855D01*
X256830Y-380559D01*
X256871Y-380533D01*
X256904Y-380500D01*
X256937Y-380470D01*
X256963Y-380441D01*
X256982Y-380411D01*
X257000Y-380389D01*
X257008Y-380374D01*
X257011Y-380371D01*
X257033Y-380323D01*
X257052Y-380274D01*
X257063Y-380230D01*
X257074Y-380186D01*
X257078Y-380149D01*
X257082Y-380119D01*
Y-380049D01*
X257074Y-380004D01*
X257056Y-379927D01*
X257030Y-379860D01*
X257004Y-379801D01*
X256974Y-379756D01*
X256948Y-379723D01*
X256930Y-379705D01*
X256926Y-379697D01*
X256922D01*
X256859Y-379645D01*
X256793Y-379608D01*
X256723Y-379583D01*
X256652Y-379564D01*
X256593Y-379553D01*
X256567Y-379549D01*
X256545D01*
X256526Y-379545D01*
X256512D01*
X256504D01*
X256501D01*
X256449D01*
X256401Y-379553D01*
X256308Y-379571D01*
X256230Y-379597D01*
X256168Y-379623D01*
X256116Y-379653D01*
X256075Y-379679D01*
X256064Y-379690D01*
X256053Y-379697D01*
X256049Y-379701D01*
X256046Y-379705D01*
X256016Y-379734D01*
X255990Y-379764D01*
X255946Y-379830D01*
X255916Y-379893D01*
X255898Y-379956D01*
X255883Y-380008D01*
X255879Y-380052D01*
X255875Y-380067D01*
Y-380089D01*
X255879Y-380160D01*
X255894Y-380223D01*
X255912Y-380278D01*
X255935Y-380323D01*
X255957Y-380363D01*
X255975Y-380393D01*
X255990Y-380408D01*
X255994Y-380415D01*
X256046Y-380459D01*
X256101Y-380496D01*
X256164Y-380526D01*
X256220Y-380548D01*
X256275Y-380563D01*
X256316Y-380574D01*
X256334Y-380578D01*
X256345Y-380581D01*
X256353D01*
X256356D01*
X256330Y-380911D01*
X256271Y-380903D01*
X256216Y-380892D01*
X256112Y-380859D01*
X256023Y-380818D01*
X255983Y-380796D01*
X255949Y-380774D01*
X255916Y-380755D01*
X255887Y-380733D01*
X255864Y-380715D01*
X255846Y-380696D01*
X255831Y-380681D01*
X255816Y-380674D01*
X255812Y-380667D01*
X255809Y-380663D01*
X255775Y-380619D01*
X255746Y-380574D01*
X255720Y-380526D01*
X255698Y-380478D01*
X255664Y-380385D01*
X255642Y-380293D01*
X255631Y-380252D01*
X255627Y-380211D01*
X255624Y-380178D01*
X255620Y-380149D01*
X255616Y-380123D01*
Y-380089D01*
X255620Y-380012D01*
X255631Y-379938D01*
X255646Y-379867D01*
X255664Y-379804D01*
X255690Y-379745D01*
X255716Y-379690D01*
X255742Y-379638D01*
X255772Y-379594D01*
X255801Y-379553D01*
X255827Y-379516D01*
X255857Y-379486D01*
X255879Y-379460D01*
X255898Y-379442D01*
X255912Y-379427D01*
X255924Y-379420D01*
X255927Y-379416D01*
X255975Y-379379D01*
X256027Y-379349D01*
X256075Y-379320D01*
X256127Y-379298D01*
X256227Y-379261D01*
X256323Y-379238D01*
X256364Y-379231D01*
X256404Y-379224D01*
X256438Y-379220D01*
X256467Y-379216D01*
X256493Y-379212D01*
X256512D01*
X256523D01*
X256526D01*
X256593Y-379216D01*
D02*
G37*
G36*
X256556Y-381540D02*
X256497Y-381555D01*
X256441Y-381573D01*
X256390Y-381592D01*
X256342Y-381610D01*
X256297Y-381632D01*
X256260Y-381655D01*
X256223Y-381680D01*
X256190Y-381703D01*
X256160Y-381721D01*
X256138Y-381743D01*
X256116Y-381762D01*
X256097Y-381777D01*
X256086Y-381791D01*
X256075Y-381803D01*
X256071Y-381806D01*
X256068Y-381810D01*
X256038Y-381847D01*
X256016Y-381888D01*
X255975Y-381969D01*
X255946Y-382047D01*
X255927Y-382124D01*
X255912Y-382191D01*
X255909Y-382217D01*
Y-382243D01*
X255905Y-382265D01*
Y-382291D01*
X255909Y-382376D01*
X255924Y-382457D01*
X255942Y-382531D01*
X255964Y-382598D01*
X255986Y-382650D01*
X255997Y-382672D01*
X256005Y-382691D01*
X256012Y-382705D01*
X256020Y-382716D01*
X256023Y-382724D01*
Y-382728D01*
X256075Y-382798D01*
X256131Y-382857D01*
X256194Y-382909D01*
X256253Y-382949D01*
X256305Y-382983D01*
X256349Y-383005D01*
X256367Y-383012D01*
X256379Y-383020D01*
X256386Y-383024D01*
X256390D01*
X256486Y-383053D01*
X256582Y-383075D01*
X256678Y-383094D01*
X256767Y-383105D01*
X256808Y-383109D01*
X256845Y-383112D01*
X256878D01*
X256904Y-383116D01*
X256926D01*
X256945D01*
X256956D01*
X256960D01*
X257056Y-383112D01*
X257144Y-383105D01*
X257226Y-383090D01*
X257300Y-383075D01*
X257363Y-383064D01*
X257389Y-383057D01*
X257411Y-383049D01*
X257429Y-383046D01*
X257440Y-383042D01*
X257448Y-383038D01*
X257452D01*
X257537Y-383001D01*
X257614Y-382961D01*
X257677Y-382916D01*
X257733Y-382868D01*
X257777Y-382827D01*
X257807Y-382794D01*
X257825Y-382768D01*
X257833Y-382765D01*
Y-382761D01*
X257881Y-382683D01*
X257918Y-382598D01*
X257944Y-382517D01*
X257958Y-382439D01*
X257969Y-382369D01*
X257973Y-382339D01*
Y-382313D01*
X257977Y-382295D01*
Y-382265D01*
X257973Y-382172D01*
X257958Y-382087D01*
X257936Y-382017D01*
X257914Y-381954D01*
X257888Y-381906D01*
X257870Y-381869D01*
X257855Y-381847D01*
X257847Y-381839D01*
X257792Y-381780D01*
X257729Y-381725D01*
X257662Y-381680D01*
X257596Y-381643D01*
X257537Y-381614D01*
X257507Y-381603D01*
X257485Y-381595D01*
X257466Y-381588D01*
X257452Y-381580D01*
X257444Y-381577D01*
X257440D01*
X257518Y-381244D01*
X257585Y-381266D01*
X257644Y-381288D01*
X257699Y-381318D01*
X257755Y-381344D01*
X257803Y-381373D01*
X257847Y-381407D01*
X257892Y-381436D01*
X257929Y-381466D01*
X257958Y-381495D01*
X257988Y-381521D01*
X258014Y-381547D01*
X258032Y-381566D01*
X258051Y-381584D01*
X258062Y-381599D01*
X258066Y-381606D01*
X258069Y-381610D01*
X258103Y-381662D01*
X258136Y-381714D01*
X258162Y-381766D01*
X258184Y-381821D01*
X258218Y-381932D01*
X258240Y-382032D01*
X258251Y-382080D01*
X258254Y-382121D01*
X258258Y-382161D01*
X258262Y-382195D01*
X258265Y-382221D01*
Y-382258D01*
X258258Y-382380D01*
X258240Y-382498D01*
X258218Y-382602D01*
X258203Y-382650D01*
X258188Y-382694D01*
X258173Y-382735D01*
X258158Y-382772D01*
X258147Y-382802D01*
X258136Y-382831D01*
X258125Y-382850D01*
X258118Y-382864D01*
X258114Y-382875D01*
X258110Y-382879D01*
X258047Y-382979D01*
X257973Y-383064D01*
X257899Y-383138D01*
X257825Y-383201D01*
X257759Y-383249D01*
X257729Y-383268D01*
X257703Y-383282D01*
X257685Y-383297D01*
X257670Y-383305D01*
X257659Y-383308D01*
X257655Y-383312D01*
X257540Y-383364D01*
X257422Y-383401D01*
X257304Y-383427D01*
X257196Y-383445D01*
X257148Y-383453D01*
X257100Y-383456D01*
X257063Y-383460D01*
X257026D01*
X257000Y-383464D01*
X256978D01*
X256963D01*
X256960D01*
X256826Y-383456D01*
X256697Y-383442D01*
X256582Y-383423D01*
X256526Y-383408D01*
X256479Y-383397D01*
X256434Y-383386D01*
X256393Y-383371D01*
X256356Y-383360D01*
X256327Y-383353D01*
X256305Y-383342D01*
X256286Y-383338D01*
X256275Y-383331D01*
X256271D01*
X256160Y-383275D01*
X256060Y-383212D01*
X255975Y-383146D01*
X255942Y-383112D01*
X255909Y-383083D01*
X255879Y-383053D01*
X255853Y-383024D01*
X255831Y-382998D01*
X255816Y-382975D01*
X255801Y-382961D01*
X255790Y-382946D01*
X255786Y-382938D01*
X255783Y-382935D01*
X255753Y-382883D01*
X255727Y-382831D01*
X255687Y-382720D01*
X255657Y-382609D01*
X255639Y-382502D01*
X255631Y-382450D01*
X255624Y-382406D01*
X255620Y-382365D01*
Y-382332D01*
X255616Y-382302D01*
Y-382261D01*
X255620Y-382187D01*
X255627Y-382117D01*
X255635Y-382050D01*
X255650Y-381988D01*
X255668Y-381928D01*
X255687Y-381873D01*
X255705Y-381821D01*
X255727Y-381773D01*
X255746Y-381732D01*
X255764Y-381692D01*
X255783Y-381662D01*
X255801Y-381632D01*
X255816Y-381614D01*
X255823Y-381595D01*
X255831Y-381588D01*
X255835Y-381584D01*
X255879Y-381532D01*
X255924Y-381488D01*
X255975Y-381447D01*
X256027Y-381407D01*
X256131Y-381340D01*
X256234Y-381288D01*
X256282Y-381266D01*
X256327Y-381247D01*
X256367Y-381233D01*
X256401Y-381222D01*
X256430Y-381210D01*
X256453Y-381203D01*
X256467Y-381199D01*
X256471D01*
X256556Y-381540D01*
D02*
G37*
G36*
X267713Y-366934D02*
X267776Y-366890D01*
X267802Y-366867D01*
X267828Y-366849D01*
X267850Y-366830D01*
X267865Y-366816D01*
X267876Y-366805D01*
X267880Y-366801D01*
X267898Y-366782D01*
X267916Y-366760D01*
X267965Y-366708D01*
X268020Y-366649D01*
X268076Y-366586D01*
X268124Y-366527D01*
X268146Y-366501D01*
X268168Y-366479D01*
X268183Y-366460D01*
X268194Y-366446D01*
X268201Y-366438D01*
X268205Y-366435D01*
X268257Y-366375D01*
X268305Y-366316D01*
X268353Y-366264D01*
X268394Y-366216D01*
X268435Y-366172D01*
X268472Y-366135D01*
X268505Y-366098D01*
X268534Y-366068D01*
X268564Y-366039D01*
X268586Y-366017D01*
X268605Y-365998D01*
X268623Y-365980D01*
X268645Y-365961D01*
X268653Y-365954D01*
X268716Y-365902D01*
X268771Y-365857D01*
X268827Y-365820D01*
X268871Y-365791D01*
X268912Y-365769D01*
X268941Y-365754D01*
X268960Y-365746D01*
X268967Y-365743D01*
X269023Y-365721D01*
X269078Y-365706D01*
X269130Y-365691D01*
X269175Y-365684D01*
X269215Y-365680D01*
X269245Y-365676D01*
X269263D01*
X269271D01*
X269326Y-365680D01*
X269378Y-365687D01*
X269430Y-365695D01*
X269474Y-365709D01*
X269563Y-365746D01*
X269633Y-365783D01*
X269667Y-365806D01*
X269692Y-365824D01*
X269718Y-365843D01*
X269737Y-365861D01*
X269752Y-365876D01*
X269766Y-365883D01*
X269770Y-365891D01*
X269774Y-365894D01*
X269811Y-365935D01*
X269844Y-365980D01*
X269870Y-366028D01*
X269892Y-366076D01*
X269929Y-366172D01*
X269955Y-366268D01*
X269963Y-366309D01*
X269970Y-366350D01*
X269974Y-366387D01*
X269977Y-366416D01*
X269981Y-366442D01*
Y-366479D01*
X269977Y-366546D01*
X269974Y-366609D01*
X269963Y-366668D01*
X269952Y-366723D01*
X269937Y-366775D01*
X269922Y-366823D01*
X269903Y-366867D01*
X269885Y-366908D01*
X269866Y-366945D01*
X269848Y-366975D01*
X269833Y-367001D01*
X269818Y-367023D01*
X269807Y-367041D01*
X269796Y-367053D01*
X269792Y-367060D01*
X269789Y-367064D01*
X269752Y-367101D01*
X269711Y-367134D01*
X269667Y-367167D01*
X269622Y-367193D01*
X269533Y-367237D01*
X269445Y-367267D01*
X269404Y-367278D01*
X269363Y-367289D01*
X269330Y-367297D01*
X269300Y-367304D01*
X269274Y-367308D01*
X269256D01*
X269245Y-367312D01*
X269241D01*
X269208Y-366990D01*
X269293Y-366982D01*
X269367Y-366967D01*
X269433Y-366945D01*
X269485Y-366919D01*
X269530Y-366897D01*
X269559Y-366875D01*
X269578Y-366860D01*
X269585Y-366853D01*
X269630Y-366797D01*
X269663Y-366738D01*
X269689Y-366675D01*
X269704Y-366620D01*
X269715Y-366568D01*
X269718Y-366523D01*
X269722Y-366509D01*
Y-366486D01*
X269718Y-366409D01*
X269704Y-366338D01*
X269681Y-366279D01*
X269659Y-366227D01*
X269633Y-366187D01*
X269615Y-366161D01*
X269600Y-366142D01*
X269593Y-366135D01*
X269541Y-366090D01*
X269489Y-366057D01*
X269437Y-366031D01*
X269385Y-366017D01*
X269345Y-366005D01*
X269308Y-366002D01*
X269285Y-365998D01*
X269282D01*
X269278D01*
X269212Y-366005D01*
X269141Y-366020D01*
X269078Y-366046D01*
X269019Y-366072D01*
X268971Y-366102D01*
X268930Y-366127D01*
X268916Y-366135D01*
X268904Y-366142D01*
X268901Y-366150D01*
X268897D01*
X268856Y-366179D01*
X268816Y-366216D01*
X268771Y-366257D01*
X268727Y-366301D01*
X268638Y-366394D01*
X268549Y-366486D01*
X268509Y-366534D01*
X268472Y-366575D01*
X268438Y-366616D01*
X268409Y-366649D01*
X268386Y-366675D01*
X268368Y-366697D01*
X268357Y-366712D01*
X268353Y-366716D01*
X268275Y-366808D01*
X268201Y-366893D01*
X268135Y-366964D01*
X268079Y-367019D01*
X268031Y-367067D01*
X267998Y-367101D01*
X267976Y-367119D01*
X267972Y-367126D01*
X267968D01*
X267905Y-367178D01*
X267846Y-367219D01*
X267787Y-367256D01*
X267735Y-367286D01*
X267691Y-367308D01*
X267657Y-367323D01*
X267635Y-367330D01*
X267632Y-367334D01*
X267628D01*
X267587Y-367349D01*
X267550Y-367356D01*
X267513Y-367363D01*
X267480Y-367367D01*
X267450Y-367371D01*
X267428D01*
X267413D01*
X267410D01*
Y-365672D01*
X267713D01*
Y-366934D01*
D02*
G37*
G36*
X268342Y-367622D02*
X268405Y-367630D01*
X268468Y-367641D01*
X268523Y-367656D01*
X268575Y-367674D01*
X268627Y-367693D01*
X268671Y-367715D01*
X268712Y-367733D01*
X268749Y-367756D01*
X268782Y-367778D01*
X268808Y-367796D01*
X268834Y-367815D01*
X268853Y-367829D01*
X268864Y-367841D01*
X268871Y-367848D01*
X268875Y-367852D01*
X268916Y-367896D01*
X268952Y-367940D01*
X268982Y-367989D01*
X269008Y-368037D01*
X269034Y-368085D01*
X269052Y-368133D01*
X269078Y-368222D01*
X269089Y-368262D01*
X269097Y-368299D01*
X269100Y-368333D01*
X269104Y-368362D01*
X269108Y-368385D01*
Y-368466D01*
X269100Y-368510D01*
X269082Y-368599D01*
X269056Y-368681D01*
X269026Y-368755D01*
X268997Y-368814D01*
X268982Y-368840D01*
X268971Y-368862D01*
X268960Y-368880D01*
X268952Y-368891D01*
X268949Y-368899D01*
X268945Y-368902D01*
X269637Y-368766D01*
Y-367741D01*
X269937D01*
Y-369014D01*
X268619Y-369261D01*
X268579Y-368965D01*
X268619Y-368939D01*
X268653Y-368906D01*
X268686Y-368877D01*
X268712Y-368847D01*
X268730Y-368817D01*
X268749Y-368795D01*
X268756Y-368780D01*
X268760Y-368777D01*
X268782Y-368729D01*
X268801Y-368681D01*
X268812Y-368636D01*
X268823Y-368592D01*
X268827Y-368555D01*
X268830Y-368525D01*
Y-368455D01*
X268823Y-368410D01*
X268805Y-368333D01*
X268779Y-368266D01*
X268753Y-368207D01*
X268723Y-368162D01*
X268697Y-368129D01*
X268679Y-368111D01*
X268675Y-368103D01*
X268671D01*
X268608Y-368052D01*
X268542Y-368015D01*
X268472Y-367989D01*
X268401Y-367970D01*
X268342Y-367959D01*
X268316Y-367955D01*
X268294D01*
X268275Y-367952D01*
X268261D01*
X268253D01*
X268250D01*
X268198D01*
X268150Y-367959D01*
X268057Y-367977D01*
X267979Y-368003D01*
X267916Y-368029D01*
X267865Y-368059D01*
X267824Y-368085D01*
X267813Y-368096D01*
X267802Y-368103D01*
X267798Y-368107D01*
X267794Y-368111D01*
X267765Y-368140D01*
X267739Y-368170D01*
X267694Y-368236D01*
X267665Y-368299D01*
X267646Y-368362D01*
X267632Y-368414D01*
X267628Y-368459D01*
X267624Y-368473D01*
Y-368495D01*
X267628Y-368566D01*
X267643Y-368629D01*
X267661Y-368684D01*
X267683Y-368729D01*
X267706Y-368769D01*
X267724Y-368799D01*
X267739Y-368814D01*
X267743Y-368821D01*
X267794Y-368865D01*
X267850Y-368902D01*
X267913Y-368932D01*
X267968Y-368954D01*
X268024Y-368969D01*
X268064Y-368980D01*
X268083Y-368984D01*
X268094Y-368988D01*
X268102D01*
X268105D01*
X268079Y-369317D01*
X268020Y-369309D01*
X267965Y-369298D01*
X267861Y-369265D01*
X267772Y-369224D01*
X267731Y-369202D01*
X267698Y-369180D01*
X267665Y-369162D01*
X267635Y-369139D01*
X267613Y-369121D01*
X267595Y-369102D01*
X267580Y-369088D01*
X267565Y-369080D01*
X267561Y-369073D01*
X267558Y-369069D01*
X267524Y-369025D01*
X267495Y-368980D01*
X267469Y-368932D01*
X267447Y-368884D01*
X267413Y-368792D01*
X267391Y-368699D01*
X267380Y-368658D01*
X267376Y-368618D01*
X267373Y-368584D01*
X267369Y-368555D01*
X267365Y-368529D01*
Y-368495D01*
X267369Y-368418D01*
X267380Y-368344D01*
X267395Y-368273D01*
X267413Y-368211D01*
X267439Y-368151D01*
X267465Y-368096D01*
X267491Y-368044D01*
X267521Y-368000D01*
X267550Y-367959D01*
X267576Y-367922D01*
X267606Y-367892D01*
X267628Y-367866D01*
X267646Y-367848D01*
X267661Y-367833D01*
X267672Y-367826D01*
X267676Y-367822D01*
X267724Y-367785D01*
X267776Y-367756D01*
X267824Y-367726D01*
X267876Y-367704D01*
X267976Y-367667D01*
X268072Y-367645D01*
X268113Y-367637D01*
X268153Y-367630D01*
X268187Y-367626D01*
X268216Y-367622D01*
X268242Y-367619D01*
X268261D01*
X268272D01*
X268275D01*
X268342Y-367622D01*
D02*
G37*
G36*
X268305Y-369946D02*
X268246Y-369961D01*
X268190Y-369979D01*
X268139Y-369998D01*
X268090Y-370016D01*
X268046Y-370038D01*
X268009Y-370061D01*
X267972Y-370087D01*
X267939Y-370109D01*
X267909Y-370127D01*
X267887Y-370149D01*
X267865Y-370168D01*
X267846Y-370183D01*
X267835Y-370198D01*
X267824Y-370209D01*
X267820Y-370212D01*
X267817Y-370216D01*
X267787Y-370253D01*
X267765Y-370294D01*
X267724Y-370375D01*
X267694Y-370453D01*
X267676Y-370531D01*
X267661Y-370597D01*
X267657Y-370623D01*
Y-370649D01*
X267654Y-370671D01*
Y-370697D01*
X267657Y-370782D01*
X267672Y-370864D01*
X267691Y-370937D01*
X267713Y-371004D01*
X267735Y-371056D01*
X267746Y-371078D01*
X267754Y-371097D01*
X267761Y-371111D01*
X267769Y-371123D01*
X267772Y-371130D01*
Y-371134D01*
X267824Y-371204D01*
X267880Y-371263D01*
X267942Y-371315D01*
X268002Y-371356D01*
X268053Y-371389D01*
X268098Y-371411D01*
X268116Y-371418D01*
X268127Y-371426D01*
X268135Y-371430D01*
X268139D01*
X268235Y-371459D01*
X268331Y-371481D01*
X268427Y-371500D01*
X268516Y-371511D01*
X268557Y-371515D01*
X268594Y-371518D01*
X268627D01*
X268653Y-371522D01*
X268675D01*
X268693D01*
X268705D01*
X268708D01*
X268805Y-371518D01*
X268893Y-371511D01*
X268975Y-371496D01*
X269049Y-371481D01*
X269112Y-371470D01*
X269138Y-371463D01*
X269160Y-371456D01*
X269178Y-371452D01*
X269189Y-371448D01*
X269197Y-371444D01*
X269200D01*
X269285Y-371407D01*
X269363Y-371367D01*
X269426Y-371322D01*
X269482Y-371274D01*
X269526Y-371234D01*
X269556Y-371200D01*
X269574Y-371174D01*
X269582Y-371171D01*
Y-371167D01*
X269630Y-371089D01*
X269667Y-371004D01*
X269692Y-370923D01*
X269707Y-370845D01*
X269718Y-370775D01*
X269722Y-370745D01*
Y-370719D01*
X269726Y-370701D01*
Y-370671D01*
X269722Y-370579D01*
X269707Y-370494D01*
X269685Y-370423D01*
X269663Y-370360D01*
X269637Y-370312D01*
X269619Y-370275D01*
X269604Y-370253D01*
X269596Y-370246D01*
X269541Y-370186D01*
X269478Y-370131D01*
X269411Y-370087D01*
X269345Y-370050D01*
X269285Y-370020D01*
X269256Y-370009D01*
X269234Y-370001D01*
X269215Y-369994D01*
X269200Y-369987D01*
X269193Y-369983D01*
X269189D01*
X269267Y-369650D01*
X269334Y-369672D01*
X269393Y-369694D01*
X269448Y-369724D01*
X269504Y-369750D01*
X269552Y-369779D01*
X269596Y-369813D01*
X269641Y-369842D01*
X269678Y-369872D01*
X269707Y-369901D01*
X269737Y-369927D01*
X269763Y-369953D01*
X269781Y-369972D01*
X269800Y-369990D01*
X269811Y-370005D01*
X269815Y-370012D01*
X269818Y-370016D01*
X269852Y-370068D01*
X269885Y-370120D01*
X269911Y-370172D01*
X269933Y-370227D01*
X269966Y-370338D01*
X269988Y-370438D01*
X270000Y-370486D01*
X270003Y-370527D01*
X270007Y-370567D01*
X270011Y-370601D01*
X270014Y-370627D01*
Y-370664D01*
X270007Y-370786D01*
X269988Y-370904D01*
X269966Y-371008D01*
X269952Y-371056D01*
X269937Y-371100D01*
X269922Y-371141D01*
X269907Y-371178D01*
X269896Y-371208D01*
X269885Y-371237D01*
X269874Y-371256D01*
X269866Y-371270D01*
X269863Y-371282D01*
X269859Y-371285D01*
X269796Y-371385D01*
X269722Y-371470D01*
X269648Y-371544D01*
X269574Y-371607D01*
X269508Y-371655D01*
X269478Y-371674D01*
X269452Y-371689D01*
X269433Y-371703D01*
X269419Y-371711D01*
X269408Y-371714D01*
X269404Y-371718D01*
X269289Y-371770D01*
X269171Y-371807D01*
X269052Y-371833D01*
X268945Y-371851D01*
X268897Y-371859D01*
X268849Y-371863D01*
X268812Y-371866D01*
X268775D01*
X268749Y-371870D01*
X268727D01*
X268712D01*
X268708D01*
X268575Y-371863D01*
X268446Y-371848D01*
X268331Y-371829D01*
X268275Y-371814D01*
X268227Y-371803D01*
X268183Y-371792D01*
X268142Y-371777D01*
X268105Y-371766D01*
X268076Y-371759D01*
X268053Y-371748D01*
X268035Y-371744D01*
X268024Y-371737D01*
X268020D01*
X267909Y-371681D01*
X267809Y-371618D01*
X267724Y-371552D01*
X267691Y-371518D01*
X267657Y-371489D01*
X267628Y-371459D01*
X267602Y-371430D01*
X267580Y-371404D01*
X267565Y-371381D01*
X267550Y-371367D01*
X267539Y-371352D01*
X267535Y-371344D01*
X267532Y-371341D01*
X267502Y-371289D01*
X267476Y-371237D01*
X267436Y-371126D01*
X267406Y-371015D01*
X267387Y-370908D01*
X267380Y-370856D01*
X267373Y-370812D01*
X267369Y-370771D01*
Y-370738D01*
X267365Y-370708D01*
Y-370667D01*
X267369Y-370593D01*
X267376Y-370523D01*
X267384Y-370457D01*
X267399Y-370394D01*
X267417Y-370334D01*
X267436Y-370279D01*
X267454Y-370227D01*
X267476Y-370179D01*
X267495Y-370138D01*
X267513Y-370098D01*
X267532Y-370068D01*
X267550Y-370038D01*
X267565Y-370020D01*
X267572Y-370001D01*
X267580Y-369994D01*
X267583Y-369990D01*
X267628Y-369938D01*
X267672Y-369894D01*
X267724Y-369853D01*
X267776Y-369813D01*
X267880Y-369746D01*
X267983Y-369694D01*
X268031Y-369672D01*
X268076Y-369654D01*
X268116Y-369639D01*
X268150Y-369628D01*
X268179Y-369617D01*
X268201Y-369609D01*
X268216Y-369605D01*
X268220D01*
X268305Y-369946D01*
D02*
G37*
G36*
X116472Y-264906D02*
X115284D01*
X115255Y-264902D01*
X115222D01*
X115144Y-264899D01*
X115062Y-264888D01*
X114974Y-264877D01*
X114892Y-264858D01*
X114851Y-264847D01*
X114818Y-264836D01*
X114815D01*
X114811Y-264832D01*
X114789Y-264821D01*
X114755Y-264806D01*
X114715Y-264780D01*
X114670Y-264747D01*
X114622Y-264703D01*
X114578Y-264651D01*
X114533Y-264592D01*
Y-264588D01*
X114530Y-264584D01*
X114515Y-264562D01*
X114500Y-264525D01*
X114478Y-264477D01*
X114459Y-264422D01*
X114441Y-264355D01*
X114430Y-264285D01*
X114426Y-264207D01*
Y-264203D01*
Y-264196D01*
Y-264181D01*
X114430Y-264162D01*
Y-264137D01*
X114433Y-264111D01*
X114448Y-264048D01*
X114471Y-263974D01*
X114500Y-263896D01*
X114544Y-263818D01*
X114574Y-263781D01*
X114604Y-263744D01*
X114607Y-263741D01*
X114611Y-263737D01*
X114622Y-263726D01*
X114637Y-263715D01*
X114655Y-263700D01*
X114678Y-263685D01*
X114707Y-263667D01*
X114737Y-263645D01*
X114774Y-263626D01*
X114815Y-263608D01*
X114859Y-263585D01*
X114907Y-263567D01*
X114963Y-263552D01*
X115018Y-263533D01*
X115081Y-263522D01*
X115148Y-263511D01*
X115140Y-263508D01*
X115125Y-263500D01*
X115103Y-263485D01*
X115074Y-263471D01*
X115007Y-263430D01*
X114974Y-263404D01*
X114944Y-263382D01*
X114937Y-263374D01*
X114918Y-263356D01*
X114889Y-263326D01*
X114851Y-263289D01*
X114811Y-263238D01*
X114763Y-263182D01*
X114715Y-263115D01*
X114663Y-263041D01*
X114223Y-262346D01*
X114644D01*
X114981Y-262879D01*
Y-262882D01*
X114988Y-262890D01*
X114996Y-262901D01*
X115007Y-262916D01*
X115033Y-262956D01*
X115066Y-263008D01*
X115107Y-263064D01*
X115148Y-263123D01*
X115188Y-263178D01*
X115225Y-263230D01*
X115229Y-263234D01*
X115240Y-263249D01*
X115259Y-263271D01*
X115284Y-263297D01*
X115340Y-263352D01*
X115370Y-263378D01*
X115399Y-263400D01*
X115403Y-263404D01*
X115410Y-263408D01*
X115425Y-263415D01*
X115447Y-263426D01*
X115470Y-263437D01*
X115495Y-263448D01*
X115554Y-263467D01*
X115558D01*
X115566Y-263471D01*
X115580D01*
X115599Y-263474D01*
X115625Y-263478D01*
X115654D01*
X115695Y-263482D01*
X116132D01*
Y-262346D01*
X116472D01*
Y-264906D01*
D02*
G37*
G36*
X114067Y-262350D02*
Y-262364D01*
Y-262386D01*
X114063Y-262416D01*
X114060Y-262449D01*
X114052Y-262486D01*
X114045Y-262523D01*
X114030Y-262564D01*
Y-262568D01*
X114026Y-262572D01*
X114019Y-262594D01*
X114004Y-262627D01*
X113982Y-262671D01*
X113952Y-262723D01*
X113916Y-262782D01*
X113875Y-262842D01*
X113823Y-262905D01*
Y-262908D01*
X113816Y-262912D01*
X113797Y-262934D01*
X113764Y-262967D01*
X113716Y-263016D01*
X113660Y-263071D01*
X113590Y-263138D01*
X113505Y-263212D01*
X113412Y-263289D01*
X113409Y-263293D01*
X113394Y-263304D01*
X113372Y-263323D01*
X113346Y-263345D01*
X113312Y-263374D01*
X113272Y-263408D01*
X113231Y-263445D01*
X113183Y-263485D01*
X113090Y-263574D01*
X112998Y-263663D01*
X112953Y-263707D01*
X112913Y-263752D01*
X112876Y-263792D01*
X112846Y-263833D01*
Y-263837D01*
X112839Y-263841D01*
X112831Y-263852D01*
X112824Y-263866D01*
X112798Y-263907D01*
X112768Y-263955D01*
X112743Y-264015D01*
X112717Y-264077D01*
X112702Y-264148D01*
X112695Y-264214D01*
Y-264218D01*
Y-264222D01*
X112698Y-264244D01*
X112702Y-264281D01*
X112713Y-264322D01*
X112728Y-264373D01*
X112754Y-264425D01*
X112787Y-264477D01*
X112831Y-264529D01*
X112839Y-264536D01*
X112857Y-264551D01*
X112883Y-264569D01*
X112924Y-264595D01*
X112976Y-264618D01*
X113035Y-264640D01*
X113105Y-264655D01*
X113183Y-264658D01*
X113205D01*
X113220Y-264655D01*
X113264Y-264651D01*
X113316Y-264640D01*
X113372Y-264625D01*
X113434Y-264599D01*
X113494Y-264566D01*
X113549Y-264521D01*
X113557Y-264514D01*
X113571Y-264495D01*
X113594Y-264466D01*
X113616Y-264422D01*
X113642Y-264370D01*
X113664Y-264303D01*
X113679Y-264229D01*
X113686Y-264144D01*
X114008Y-264177D01*
Y-264181D01*
X114004Y-264192D01*
Y-264211D01*
X114000Y-264236D01*
X113993Y-264266D01*
X113986Y-264299D01*
X113975Y-264340D01*
X113964Y-264381D01*
X113934Y-264470D01*
X113890Y-264558D01*
X113864Y-264603D01*
X113830Y-264647D01*
X113797Y-264688D01*
X113760Y-264725D01*
X113756Y-264729D01*
X113749Y-264732D01*
X113738Y-264743D01*
X113719Y-264755D01*
X113697Y-264769D01*
X113671Y-264784D01*
X113642Y-264803D01*
X113605Y-264821D01*
X113564Y-264840D01*
X113520Y-264858D01*
X113471Y-264873D01*
X113420Y-264888D01*
X113364Y-264899D01*
X113305Y-264910D01*
X113242Y-264914D01*
X113175Y-264917D01*
X113138D01*
X113113Y-264914D01*
X113083Y-264910D01*
X113046Y-264906D01*
X113005Y-264899D01*
X112965Y-264891D01*
X112868Y-264865D01*
X112772Y-264828D01*
X112724Y-264806D01*
X112676Y-264780D01*
X112631Y-264747D01*
X112591Y-264710D01*
X112587Y-264706D01*
X112580Y-264703D01*
X112572Y-264688D01*
X112557Y-264673D01*
X112539Y-264655D01*
X112521Y-264629D01*
X112502Y-264603D01*
X112480Y-264569D01*
X112443Y-264499D01*
X112406Y-264410D01*
X112391Y-264366D01*
X112384Y-264314D01*
X112376Y-264262D01*
X112373Y-264207D01*
Y-264199D01*
Y-264181D01*
X112376Y-264151D01*
X112380Y-264111D01*
X112387Y-264066D01*
X112402Y-264015D01*
X112417Y-263959D01*
X112439Y-263903D01*
X112443Y-263896D01*
X112450Y-263878D01*
X112465Y-263848D01*
X112487Y-263807D01*
X112517Y-263763D01*
X112554Y-263707D01*
X112598Y-263652D01*
X112650Y-263589D01*
X112657Y-263582D01*
X112676Y-263559D01*
X112695Y-263541D01*
X112713Y-263522D01*
X112735Y-263500D01*
X112765Y-263471D01*
X112794Y-263441D01*
X112831Y-263408D01*
X112868Y-263371D01*
X112913Y-263330D01*
X112961Y-263289D01*
X113013Y-263241D01*
X113072Y-263193D01*
X113131Y-263141D01*
X113135Y-263138D01*
X113142Y-263130D01*
X113157Y-263119D01*
X113175Y-263104D01*
X113198Y-263082D01*
X113224Y-263060D01*
X113283Y-263012D01*
X113346Y-262956D01*
X113405Y-262901D01*
X113457Y-262853D01*
X113479Y-262834D01*
X113497Y-262816D01*
X113501Y-262812D01*
X113512Y-262801D01*
X113527Y-262786D01*
X113546Y-262764D01*
X113564Y-262738D01*
X113586Y-262712D01*
X113630Y-262649D01*
X112369D01*
Y-262346D01*
X114067D01*
Y-262350D01*
D02*
G37*
G36*
X112076D02*
Y-262364D01*
Y-262386D01*
X112073Y-262416D01*
X112069Y-262449D01*
X112062Y-262486D01*
X112054Y-262523D01*
X112040Y-262564D01*
Y-262568D01*
X112036Y-262572D01*
X112028Y-262594D01*
X112014Y-262627D01*
X111992Y-262671D01*
X111962Y-262723D01*
X111925Y-262782D01*
X111884Y-262842D01*
X111832Y-262905D01*
Y-262908D01*
X111825Y-262912D01*
X111806Y-262934D01*
X111773Y-262967D01*
X111725Y-263016D01*
X111670Y-263071D01*
X111599Y-263138D01*
X111514Y-263212D01*
X111422Y-263289D01*
X111418Y-263293D01*
X111403Y-263304D01*
X111381Y-263323D01*
X111355Y-263345D01*
X111322Y-263374D01*
X111281Y-263408D01*
X111240Y-263445D01*
X111192Y-263485D01*
X111100Y-263574D01*
X111007Y-263663D01*
X110963Y-263707D01*
X110922Y-263752D01*
X110885Y-263792D01*
X110855Y-263833D01*
Y-263837D01*
X110848Y-263841D01*
X110841Y-263852D01*
X110833Y-263866D01*
X110807Y-263907D01*
X110778Y-263955D01*
X110752Y-264015D01*
X110726Y-264077D01*
X110711Y-264148D01*
X110704Y-264214D01*
Y-264218D01*
Y-264222D01*
X110707Y-264244D01*
X110711Y-264281D01*
X110722Y-264322D01*
X110737Y-264373D01*
X110763Y-264425D01*
X110796Y-264477D01*
X110841Y-264529D01*
X110848Y-264536D01*
X110867Y-264551D01*
X110893Y-264569D01*
X110933Y-264595D01*
X110985Y-264618D01*
X111044Y-264640D01*
X111115Y-264655D01*
X111192Y-264658D01*
X111214D01*
X111229Y-264655D01*
X111274Y-264651D01*
X111326Y-264640D01*
X111381Y-264625D01*
X111444Y-264599D01*
X111503Y-264566D01*
X111558Y-264521D01*
X111566Y-264514D01*
X111581Y-264495D01*
X111603Y-264466D01*
X111625Y-264422D01*
X111651Y-264370D01*
X111673Y-264303D01*
X111688Y-264229D01*
X111696Y-264144D01*
X112017Y-264177D01*
Y-264181D01*
X112014Y-264192D01*
Y-264211D01*
X112010Y-264236D01*
X112003Y-264266D01*
X111995Y-264299D01*
X111984Y-264340D01*
X111973Y-264381D01*
X111943Y-264470D01*
X111899Y-264558D01*
X111873Y-264603D01*
X111840Y-264647D01*
X111806Y-264688D01*
X111769Y-264725D01*
X111766Y-264729D01*
X111758Y-264732D01*
X111747Y-264743D01*
X111729Y-264755D01*
X111706Y-264769D01*
X111681Y-264784D01*
X111651Y-264803D01*
X111614Y-264821D01*
X111573Y-264840D01*
X111529Y-264858D01*
X111481Y-264873D01*
X111429Y-264888D01*
X111374Y-264899D01*
X111314Y-264910D01*
X111251Y-264914D01*
X111185Y-264917D01*
X111148D01*
X111122Y-264914D01*
X111092Y-264910D01*
X111055Y-264906D01*
X111015Y-264899D01*
X110974Y-264891D01*
X110878Y-264865D01*
X110782Y-264828D01*
X110733Y-264806D01*
X110685Y-264780D01*
X110641Y-264747D01*
X110600Y-264710D01*
X110597Y-264706D01*
X110589Y-264703D01*
X110582Y-264688D01*
X110567Y-264673D01*
X110548Y-264655D01*
X110530Y-264629D01*
X110511Y-264603D01*
X110489Y-264569D01*
X110452Y-264499D01*
X110415Y-264410D01*
X110400Y-264366D01*
X110393Y-264314D01*
X110386Y-264262D01*
X110382Y-264207D01*
Y-264199D01*
Y-264181D01*
X110386Y-264151D01*
X110389Y-264111D01*
X110397Y-264066D01*
X110412Y-264015D01*
X110426Y-263959D01*
X110449Y-263903D01*
X110452Y-263896D01*
X110460Y-263878D01*
X110475Y-263848D01*
X110497Y-263807D01*
X110526Y-263763D01*
X110563Y-263707D01*
X110608Y-263652D01*
X110659Y-263589D01*
X110667Y-263582D01*
X110685Y-263559D01*
X110704Y-263541D01*
X110722Y-263522D01*
X110745Y-263500D01*
X110774Y-263471D01*
X110804Y-263441D01*
X110841Y-263408D01*
X110878Y-263371D01*
X110922Y-263330D01*
X110970Y-263289D01*
X111022Y-263241D01*
X111081Y-263193D01*
X111141Y-263141D01*
X111144Y-263138D01*
X111152Y-263130D01*
X111166Y-263119D01*
X111185Y-263104D01*
X111207Y-263082D01*
X111233Y-263060D01*
X111292Y-263012D01*
X111355Y-262956D01*
X111414Y-262901D01*
X111466Y-262853D01*
X111488Y-262834D01*
X111507Y-262816D01*
X111510Y-262812D01*
X111522Y-262801D01*
X111536Y-262786D01*
X111555Y-262764D01*
X111573Y-262738D01*
X111596Y-262712D01*
X111640Y-262649D01*
X110378D01*
Y-262346D01*
X112076D01*
Y-262350D01*
D02*
G37*
G36*
X147238Y-342327D02*
X147286Y-342334D01*
X147345Y-342345D01*
X147412Y-342364D01*
X147479Y-342386D01*
X147545Y-342416D01*
X147549D01*
X147553Y-342419D01*
X147575Y-342430D01*
X147608Y-342453D01*
X147645Y-342479D01*
X147690Y-342516D01*
X147734Y-342556D01*
X147778Y-342604D01*
X147815Y-342660D01*
X147819Y-342667D01*
X147830Y-342686D01*
X147845Y-342719D01*
X147863Y-342760D01*
X147882Y-342808D01*
X147897Y-342863D01*
X147908Y-342926D01*
X147912Y-342989D01*
Y-342997D01*
Y-343019D01*
X147908Y-343048D01*
X147900Y-343089D01*
X147889Y-343137D01*
X147871Y-343189D01*
X147849Y-343241D01*
X147819Y-343293D01*
X147815Y-343300D01*
X147804Y-343315D01*
X147782Y-343341D01*
X147752Y-343370D01*
X147715Y-343404D01*
X147671Y-343441D01*
X147619Y-343474D01*
X147556Y-343507D01*
X147560D01*
X147567Y-343511D01*
X147579Y-343515D01*
X147593Y-343518D01*
X147634Y-343533D01*
X147686Y-343555D01*
X147745Y-343585D01*
X147804Y-343622D01*
X147860Y-343670D01*
X147912Y-343725D01*
X147915Y-343733D01*
X147930Y-343755D01*
X147952Y-343792D01*
X147975Y-343840D01*
X147997Y-343899D01*
X148019Y-343970D01*
X148034Y-344051D01*
X148037Y-344140D01*
Y-344144D01*
Y-344155D01*
Y-344173D01*
X148034Y-344195D01*
X148030Y-344225D01*
X148023Y-344258D01*
X148015Y-344295D01*
X148008Y-344336D01*
X147978Y-344425D01*
X147956Y-344473D01*
X147934Y-344517D01*
X147904Y-344565D01*
X147871Y-344614D01*
X147834Y-344662D01*
X147790Y-344706D01*
X147786Y-344710D01*
X147778Y-344717D01*
X147764Y-344728D01*
X147745Y-344743D01*
X147723Y-344761D01*
X147693Y-344780D01*
X147660Y-344802D01*
X147619Y-344821D01*
X147579Y-344843D01*
X147530Y-344865D01*
X147482Y-344884D01*
X147427Y-344902D01*
X147368Y-344917D01*
X147305Y-344928D01*
X147242Y-344935D01*
X147172Y-344939D01*
X147138D01*
X147116Y-344935D01*
X147087Y-344932D01*
X147053Y-344928D01*
X147016Y-344921D01*
X146976Y-344913D01*
X146887Y-344891D01*
X146794Y-344854D01*
X146746Y-344832D01*
X146702Y-344806D01*
X146657Y-344773D01*
X146613Y-344739D01*
X146609Y-344736D01*
X146602Y-344728D01*
X146591Y-344717D01*
X146580Y-344702D01*
X146561Y-344684D01*
X146543Y-344658D01*
X146520Y-344632D01*
X146498Y-344599D01*
X146476Y-344562D01*
X146454Y-344525D01*
X146413Y-344436D01*
X146380Y-344332D01*
X146369Y-344277D01*
X146361Y-344218D01*
X146676Y-344177D01*
Y-344181D01*
X146679Y-344188D01*
X146683Y-344203D01*
X146687Y-344221D01*
X146691Y-344244D01*
X146698Y-344269D01*
X146716Y-344325D01*
X146742Y-344391D01*
X146776Y-344454D01*
X146813Y-344514D01*
X146857Y-344565D01*
X146864Y-344569D01*
X146879Y-344584D01*
X146909Y-344602D01*
X146946Y-344621D01*
X146990Y-344643D01*
X147046Y-344662D01*
X147109Y-344676D01*
X147175Y-344680D01*
X147197D01*
X147212Y-344676D01*
X147253Y-344673D01*
X147305Y-344662D01*
X147364Y-344643D01*
X147427Y-344617D01*
X147490Y-344580D01*
X147549Y-344528D01*
X147556Y-344521D01*
X147575Y-344499D01*
X147597Y-344465D01*
X147627Y-344421D01*
X147656Y-344366D01*
X147678Y-344303D01*
X147697Y-344229D01*
X147704Y-344147D01*
Y-344144D01*
Y-344136D01*
Y-344125D01*
X147701Y-344110D01*
X147697Y-344070D01*
X147686Y-344022D01*
X147671Y-343962D01*
X147645Y-343903D01*
X147608Y-343844D01*
X147560Y-343788D01*
X147553Y-343781D01*
X147534Y-343766D01*
X147505Y-343744D01*
X147464Y-343718D01*
X147412Y-343692D01*
X147349Y-343670D01*
X147279Y-343655D01*
X147201Y-343648D01*
X147168D01*
X147142Y-343652D01*
X147109Y-343655D01*
X147072Y-343663D01*
X147027Y-343670D01*
X146979Y-343681D01*
X147016Y-343404D01*
X147035D01*
X147049Y-343407D01*
X147098D01*
X147138Y-343400D01*
X147186Y-343392D01*
X147242Y-343381D01*
X147305Y-343363D01*
X147364Y-343337D01*
X147427Y-343304D01*
X147431D01*
X147434Y-343300D01*
X147453Y-343285D01*
X147479Y-343259D01*
X147508Y-343226D01*
X147538Y-343178D01*
X147564Y-343122D01*
X147582Y-343059D01*
X147590Y-343022D01*
Y-342982D01*
Y-342978D01*
Y-342974D01*
Y-342952D01*
X147582Y-342923D01*
X147575Y-342882D01*
X147560Y-342838D01*
X147542Y-342789D01*
X147512Y-342741D01*
X147471Y-342697D01*
X147468Y-342693D01*
X147449Y-342678D01*
X147423Y-342660D01*
X147390Y-342638D01*
X147345Y-342619D01*
X147294Y-342601D01*
X147234Y-342586D01*
X147168Y-342582D01*
X147138D01*
X147105Y-342590D01*
X147061Y-342597D01*
X147012Y-342612D01*
X146964Y-342630D01*
X146913Y-342660D01*
X146864Y-342697D01*
X146861Y-342701D01*
X146846Y-342719D01*
X146824Y-342745D01*
X146798Y-342782D01*
X146772Y-342830D01*
X146746Y-342889D01*
X146724Y-342960D01*
X146709Y-343041D01*
X146395Y-342986D01*
Y-342982D01*
X146398Y-342971D01*
X146402Y-342956D01*
X146406Y-342934D01*
X146413Y-342908D01*
X146424Y-342878D01*
X146446Y-342808D01*
X146483Y-342726D01*
X146528Y-342645D01*
X146583Y-342567D01*
X146654Y-342497D01*
X146657Y-342493D01*
X146665Y-342490D01*
X146676Y-342482D01*
X146691Y-342471D01*
X146709Y-342456D01*
X146735Y-342442D01*
X146761Y-342427D01*
X146794Y-342408D01*
X146868Y-342379D01*
X146953Y-342349D01*
X147053Y-342331D01*
X147105Y-342323D01*
X147197D01*
X147238Y-342327D01*
D02*
G37*
G36*
X145277D02*
X145307Y-342331D01*
X145344Y-342334D01*
X145385Y-342342D01*
X145425Y-342349D01*
X145521Y-342375D01*
X145618Y-342412D01*
X145666Y-342434D01*
X145714Y-342460D01*
X145758Y-342493D01*
X145799Y-342530D01*
X145803Y-342534D01*
X145810Y-342538D01*
X145817Y-342553D01*
X145832Y-342567D01*
X145851Y-342586D01*
X145869Y-342612D01*
X145888Y-342638D01*
X145910Y-342671D01*
X145947Y-342741D01*
X145984Y-342830D01*
X145999Y-342875D01*
X146006Y-342926D01*
X146013Y-342978D01*
X146017Y-343034D01*
Y-343041D01*
Y-343059D01*
X146013Y-343089D01*
X146010Y-343130D01*
X146002Y-343174D01*
X145988Y-343226D01*
X145973Y-343282D01*
X145951Y-343337D01*
X145947Y-343344D01*
X145940Y-343363D01*
X145925Y-343392D01*
X145903Y-343433D01*
X145873Y-343478D01*
X145836Y-343533D01*
X145791Y-343589D01*
X145740Y-343652D01*
X145732Y-343659D01*
X145714Y-343681D01*
X145695Y-343700D01*
X145677Y-343718D01*
X145655Y-343740D01*
X145625Y-343770D01*
X145595Y-343799D01*
X145558Y-343833D01*
X145521Y-343870D01*
X145477Y-343911D01*
X145429Y-343951D01*
X145377Y-343999D01*
X145318Y-344047D01*
X145259Y-344099D01*
X145255Y-344103D01*
X145248Y-344110D01*
X145233Y-344121D01*
X145214Y-344136D01*
X145192Y-344158D01*
X145166Y-344181D01*
X145107Y-344229D01*
X145044Y-344284D01*
X144985Y-344340D01*
X144933Y-344388D01*
X144911Y-344406D01*
X144892Y-344425D01*
X144889Y-344428D01*
X144878Y-344440D01*
X144863Y-344454D01*
X144844Y-344477D01*
X144826Y-344502D01*
X144804Y-344528D01*
X144759Y-344591D01*
X146021D01*
Y-344895D01*
X144323D01*
Y-344891D01*
Y-344876D01*
Y-344854D01*
X144326Y-344824D01*
X144330Y-344791D01*
X144337Y-344754D01*
X144345Y-344717D01*
X144360Y-344676D01*
Y-344673D01*
X144363Y-344669D01*
X144371Y-344647D01*
X144386Y-344614D01*
X144408Y-344569D01*
X144437Y-344517D01*
X144474Y-344458D01*
X144515Y-344399D01*
X144567Y-344336D01*
Y-344332D01*
X144574Y-344329D01*
X144593Y-344306D01*
X144626Y-344273D01*
X144674Y-344225D01*
X144730Y-344169D01*
X144800Y-344103D01*
X144885Y-344029D01*
X144977Y-343951D01*
X144981Y-343948D01*
X144996Y-343936D01*
X145018Y-343918D01*
X145044Y-343896D01*
X145077Y-343866D01*
X145118Y-343833D01*
X145159Y-343796D01*
X145207Y-343755D01*
X145299Y-343666D01*
X145392Y-343578D01*
X145436Y-343533D01*
X145477Y-343489D01*
X145514Y-343448D01*
X145544Y-343407D01*
Y-343404D01*
X145551Y-343400D01*
X145558Y-343389D01*
X145566Y-343374D01*
X145592Y-343333D01*
X145621Y-343285D01*
X145647Y-343226D01*
X145673Y-343163D01*
X145688Y-343093D01*
X145695Y-343026D01*
Y-343022D01*
Y-343019D01*
X145692Y-342997D01*
X145688Y-342960D01*
X145677Y-342919D01*
X145662Y-342867D01*
X145636Y-342815D01*
X145603Y-342763D01*
X145558Y-342712D01*
X145551Y-342704D01*
X145533Y-342689D01*
X145507Y-342671D01*
X145466Y-342645D01*
X145414Y-342623D01*
X145355Y-342601D01*
X145285Y-342586D01*
X145207Y-342582D01*
X145185D01*
X145170Y-342586D01*
X145125Y-342590D01*
X145074Y-342601D01*
X145018Y-342616D01*
X144955Y-342641D01*
X144896Y-342675D01*
X144841Y-342719D01*
X144833Y-342726D01*
X144818Y-342745D01*
X144796Y-342775D01*
X144774Y-342819D01*
X144748Y-342871D01*
X144726Y-342937D01*
X144711Y-343011D01*
X144704Y-343096D01*
X144382Y-343063D01*
Y-343059D01*
X144386Y-343048D01*
Y-343030D01*
X144389Y-343004D01*
X144397Y-342974D01*
X144404Y-342941D01*
X144415Y-342900D01*
X144426Y-342860D01*
X144456Y-342771D01*
X144500Y-342682D01*
X144526Y-342638D01*
X144559Y-342593D01*
X144593Y-342553D01*
X144630Y-342516D01*
X144633Y-342512D01*
X144641Y-342508D01*
X144652Y-342497D01*
X144670Y-342486D01*
X144693Y-342471D01*
X144719Y-342456D01*
X144748Y-342438D01*
X144785Y-342419D01*
X144826Y-342401D01*
X144870Y-342382D01*
X144918Y-342368D01*
X144970Y-342353D01*
X145026Y-342342D01*
X145085Y-342331D01*
X145148Y-342327D01*
X145214Y-342323D01*
X145251D01*
X145277Y-342327D01*
D02*
G37*
G36*
X143135Y-342338D02*
X143168D01*
X143246Y-342342D01*
X143327Y-342353D01*
X143416Y-342364D01*
X143498Y-342382D01*
X143538Y-342393D01*
X143571Y-342405D01*
X143575D01*
X143579Y-342408D01*
X143601Y-342419D01*
X143634Y-342434D01*
X143675Y-342460D01*
X143719Y-342493D01*
X143768Y-342538D01*
X143812Y-342590D01*
X143856Y-342649D01*
Y-342653D01*
X143860Y-342656D01*
X143875Y-342678D01*
X143890Y-342715D01*
X143912Y-342763D01*
X143930Y-342819D01*
X143949Y-342886D01*
X143960Y-342956D01*
X143964Y-343034D01*
Y-343037D01*
Y-343045D01*
Y-343059D01*
X143960Y-343078D01*
Y-343104D01*
X143956Y-343130D01*
X143941Y-343193D01*
X143919Y-343267D01*
X143890Y-343344D01*
X143845Y-343422D01*
X143816Y-343459D01*
X143786Y-343496D01*
X143782Y-343500D01*
X143779Y-343503D01*
X143768Y-343515D01*
X143753Y-343526D01*
X143734Y-343541D01*
X143712Y-343555D01*
X143683Y-343574D01*
X143653Y-343596D01*
X143616Y-343615D01*
X143575Y-343633D01*
X143531Y-343655D01*
X143483Y-343674D01*
X143427Y-343689D01*
X143372Y-343707D01*
X143309Y-343718D01*
X143242Y-343729D01*
X143250Y-343733D01*
X143264Y-343740D01*
X143287Y-343755D01*
X143316Y-343770D01*
X143383Y-343811D01*
X143416Y-343836D01*
X143446Y-343859D01*
X143453Y-343866D01*
X143472Y-343885D01*
X143501Y-343914D01*
X143538Y-343951D01*
X143579Y-344003D01*
X143627Y-344058D01*
X143675Y-344125D01*
X143727Y-344199D01*
X144167Y-344895D01*
X143745D01*
X143409Y-344362D01*
Y-344358D01*
X143401Y-344351D01*
X143394Y-344340D01*
X143383Y-344325D01*
X143357Y-344284D01*
X143324Y-344232D01*
X143283Y-344177D01*
X143242Y-344118D01*
X143201Y-344062D01*
X143165Y-344010D01*
X143161Y-344007D01*
X143150Y-343992D01*
X143131Y-343970D01*
X143105Y-343944D01*
X143050Y-343888D01*
X143020Y-343862D01*
X142991Y-343840D01*
X142987Y-343836D01*
X142980Y-343833D01*
X142965Y-343825D01*
X142943Y-343814D01*
X142920Y-343803D01*
X142894Y-343792D01*
X142835Y-343774D01*
X142832D01*
X142824Y-343770D01*
X142809D01*
X142791Y-343766D01*
X142765Y-343762D01*
X142735D01*
X142695Y-343759D01*
X142258D01*
Y-344895D01*
X141918D01*
Y-342334D01*
X143105D01*
X143135Y-342338D01*
D02*
G37*
%LPC*%
G36*
X518484Y-330739D02*
X517892D01*
Y-332693D01*
X518499D01*
X518524Y-332689D01*
X518580Y-332685D01*
X518643Y-332681D01*
X518709Y-332674D01*
X518776Y-332663D01*
X518831Y-332648D01*
X518839Y-332644D01*
X518857Y-332641D01*
X518883Y-332630D01*
X518917Y-332615D01*
X518954Y-332593D01*
X518991Y-332570D01*
X519028Y-332544D01*
X519065Y-332515D01*
X519068Y-332507D01*
X519083Y-332493D01*
X519105Y-332467D01*
X519131Y-332430D01*
X519161Y-332382D01*
X519194Y-332326D01*
X519224Y-332263D01*
X519250Y-332193D01*
Y-332189D01*
X519253Y-332182D01*
X519257Y-332171D01*
X519261Y-332156D01*
X519264Y-332137D01*
X519272Y-332112D01*
X519279Y-332086D01*
X519287Y-332056D01*
X519298Y-331982D01*
X519309Y-331897D01*
X519316Y-331801D01*
X519320Y-331697D01*
Y-331694D01*
Y-331679D01*
Y-331660D01*
X519316Y-331631D01*
Y-331597D01*
X519312Y-331560D01*
X519309Y-331516D01*
X519305Y-331471D01*
X519287Y-331372D01*
X519264Y-331268D01*
X519231Y-331172D01*
X519209Y-331124D01*
X519187Y-331083D01*
Y-331079D01*
X519179Y-331072D01*
X519172Y-331061D01*
X519165Y-331046D01*
X519135Y-331009D01*
X519098Y-330965D01*
X519050Y-330917D01*
X518994Y-330868D01*
X518931Y-330828D01*
X518865Y-330794D01*
X518857Y-330791D01*
X518839Y-330787D01*
X518806Y-330776D01*
X518757Y-330765D01*
X518698Y-330757D01*
X518624Y-330746D01*
X518580Y-330743D01*
X518532D01*
X518484Y-330739D01*
D02*
G37*
G36*
X520774Y-347759D02*
X520751D01*
X520737Y-347763D01*
X520700Y-347767D01*
X520648Y-347778D01*
X520592Y-347796D01*
X520529Y-347826D01*
X520470Y-347863D01*
X520411Y-347915D01*
X520404Y-347922D01*
X520389Y-347941D01*
X520363Y-347974D01*
X520337Y-348022D01*
X520311Y-348078D01*
X520285Y-348148D01*
X520270Y-348226D01*
X520263Y-348314D01*
Y-348322D01*
Y-348340D01*
X520267Y-348374D01*
X520270Y-348414D01*
X520278Y-348462D01*
X520293Y-348514D01*
X520307Y-348570D01*
X520330Y-348625D01*
X520333Y-348633D01*
X520344Y-348651D01*
X520359Y-348677D01*
X520381Y-348710D01*
X520407Y-348744D01*
X520441Y-348784D01*
X520478Y-348818D01*
X520522Y-348851D01*
X520529Y-348855D01*
X520544Y-348862D01*
X520570Y-348877D01*
X520603Y-348888D01*
X520640Y-348903D01*
X520685Y-348918D01*
X520733Y-348925D01*
X520785Y-348929D01*
X520803D01*
X520818Y-348925D01*
X520855Y-348921D01*
X520903Y-348910D01*
X520955Y-348888D01*
X521014Y-348862D01*
X521073Y-348821D01*
X521103Y-348799D01*
X521129Y-348769D01*
Y-348766D01*
X521136Y-348762D01*
X521151Y-348740D01*
X521173Y-348703D01*
X521203Y-348655D01*
X521229Y-348592D01*
X521251Y-348518D01*
X521266Y-348433D01*
X521273Y-348333D01*
Y-348329D01*
Y-348322D01*
Y-348307D01*
X521269Y-348288D01*
Y-348266D01*
X521266Y-348240D01*
X521255Y-348181D01*
X521240Y-348115D01*
X521214Y-348044D01*
X521177Y-347978D01*
X521129Y-347915D01*
X521122Y-347907D01*
X521103Y-347889D01*
X521073Y-347867D01*
X521033Y-347837D01*
X520981Y-347808D01*
X520922Y-347785D01*
X520851Y-347767D01*
X520774Y-347759D01*
D02*
G37*
G36*
X518395Y-346886D02*
X517802D01*
Y-348840D01*
X518409D01*
X518435Y-348836D01*
X518491Y-348832D01*
X518554Y-348829D01*
X518620Y-348821D01*
X518687Y-348810D01*
X518742Y-348795D01*
X518750Y-348792D01*
X518768Y-348788D01*
X518794Y-348777D01*
X518827Y-348762D01*
X518864Y-348740D01*
X518901Y-348718D01*
X518938Y-348692D01*
X518975Y-348662D01*
X518979Y-348655D01*
X518994Y-348640D01*
X519016Y-348614D01*
X519042Y-348577D01*
X519072Y-348529D01*
X519105Y-348474D01*
X519135Y-348411D01*
X519161Y-348340D01*
Y-348337D01*
X519164Y-348329D01*
X519168Y-348318D01*
X519172Y-348303D01*
X519175Y-348285D01*
X519183Y-348259D01*
X519190Y-348233D01*
X519198Y-348203D01*
X519209Y-348129D01*
X519220Y-348044D01*
X519227Y-347948D01*
X519231Y-347845D01*
Y-347841D01*
Y-347826D01*
Y-347808D01*
X519227Y-347778D01*
Y-347745D01*
X519223Y-347708D01*
X519220Y-347663D01*
X519216Y-347619D01*
X519198Y-347519D01*
X519175Y-347415D01*
X519142Y-347319D01*
X519120Y-347271D01*
X519098Y-347230D01*
Y-347227D01*
X519090Y-347219D01*
X519083Y-347208D01*
X519075Y-347193D01*
X519046Y-347156D01*
X519009Y-347112D01*
X518961Y-347064D01*
X518905Y-347016D01*
X518842Y-346975D01*
X518776Y-346942D01*
X518768Y-346938D01*
X518750Y-346934D01*
X518716Y-346923D01*
X518668Y-346912D01*
X518609Y-346905D01*
X518535Y-346894D01*
X518491Y-346890D01*
X518443D01*
X518395Y-346886D01*
D02*
G37*
G36*
X638001Y-323075D02*
X636048D01*
Y-323682D01*
X636051Y-323708D01*
X636055Y-323763D01*
X636059Y-323826D01*
X636066Y-323893D01*
X636077Y-323960D01*
X636092Y-324015D01*
X636096Y-324023D01*
X636099Y-324041D01*
X636111Y-324067D01*
X636125Y-324100D01*
X636148Y-324137D01*
X636170Y-324174D01*
X636196Y-324211D01*
X636225Y-324248D01*
X636233Y-324252D01*
X636247Y-324267D01*
X636273Y-324289D01*
X636310Y-324315D01*
X636358Y-324344D01*
X636414Y-324378D01*
X636477Y-324407D01*
X636547Y-324433D01*
X636551D01*
X636558Y-324437D01*
X636569Y-324441D01*
X636584Y-324444D01*
X636603Y-324448D01*
X636629Y-324455D01*
X636655Y-324463D01*
X636684Y-324470D01*
X636758Y-324481D01*
X636843Y-324492D01*
X636939Y-324500D01*
X637043Y-324503D01*
X637047D01*
X637062D01*
X637080D01*
X637110Y-324500D01*
X637143D01*
X637180Y-324496D01*
X637224Y-324492D01*
X637269Y-324489D01*
X637369Y-324470D01*
X637472Y-324448D01*
X637568Y-324415D01*
X637616Y-324393D01*
X637657Y-324370D01*
X637661D01*
X637668Y-324363D01*
X637679Y-324356D01*
X637694Y-324348D01*
X637731Y-324319D01*
X637776Y-324282D01*
X637824Y-324233D01*
X637872Y-324178D01*
X637913Y-324115D01*
X637946Y-324048D01*
X637950Y-324041D01*
X637953Y-324023D01*
X637964Y-323989D01*
X637975Y-323941D01*
X637983Y-323882D01*
X637994Y-323808D01*
X637998Y-323763D01*
Y-323715D01*
X638001Y-323667D01*
Y-323075D01*
D02*
G37*
G36*
X637661Y-325610D02*
X637657D01*
X637653D01*
X637631Y-325613D01*
X637598Y-325617D01*
X637557Y-325625D01*
X637509Y-325639D01*
X637461Y-325658D01*
X637409Y-325688D01*
X637365Y-325725D01*
X637361Y-325728D01*
X637346Y-325747D01*
X637328Y-325773D01*
X637309Y-325806D01*
X637287Y-325850D01*
X637269Y-325902D01*
X637254Y-325961D01*
X637250Y-326028D01*
Y-326035D01*
X637254Y-326058D01*
X637258Y-326091D01*
X637265Y-326135D01*
X637280Y-326183D01*
X637298Y-326231D01*
X637328Y-326283D01*
X637365Y-326328D01*
X637369Y-326331D01*
X637387Y-326346D01*
X637409Y-326365D01*
X637443Y-326387D01*
X637483Y-326409D01*
X637531Y-326428D01*
X637587Y-326442D01*
X637646Y-326446D01*
X637650D01*
X637653D01*
X637676D01*
X637709Y-326439D01*
X637750Y-326431D01*
X637794Y-326416D01*
X637842Y-326394D01*
X637890Y-326365D01*
X637938Y-326324D01*
X637942Y-326320D01*
X637957Y-326302D01*
X637975Y-326276D01*
X637998Y-326242D01*
X638020Y-326198D01*
X638038Y-326150D01*
X638053Y-326091D01*
X638057Y-326028D01*
Y-325998D01*
X638049Y-325965D01*
X638042Y-325921D01*
X638027Y-325872D01*
X638009Y-325821D01*
X637979Y-325773D01*
X637938Y-325725D01*
X637935Y-325721D01*
X637920Y-325706D01*
X637894Y-325688D01*
X637861Y-325669D01*
X637820Y-325647D01*
X637772Y-325628D01*
X637720Y-325613D01*
X637661Y-325610D01*
D02*
G37*
G36*
X636481Y-325506D02*
X636473D01*
X636458D01*
X636433Y-325510D01*
X636399Y-325514D01*
X636358Y-325521D01*
X636314Y-325532D01*
X636270Y-325547D01*
X636222Y-325565D01*
X636218Y-325569D01*
X636199Y-325576D01*
X636177Y-325591D01*
X636151Y-325613D01*
X636118Y-325639D01*
X636085Y-325673D01*
X636055Y-325710D01*
X636025Y-325754D01*
X636022Y-325762D01*
X636014Y-325776D01*
X636003Y-325802D01*
X635992Y-325835D01*
X635981Y-325876D01*
X635970Y-325924D01*
X635963Y-325976D01*
X635959Y-326028D01*
Y-326050D01*
X635963Y-326065D01*
X635966Y-326109D01*
X635977Y-326161D01*
X635996Y-326220D01*
X636018Y-326283D01*
X636055Y-326342D01*
X636103Y-326402D01*
X636111Y-326409D01*
X636129Y-326424D01*
X636162Y-326450D01*
X636203Y-326476D01*
X636255Y-326501D01*
X636318Y-326527D01*
X636392Y-326542D01*
X636470Y-326550D01*
X636473D01*
X636481D01*
X636492D01*
X636507Y-326546D01*
X636547Y-326542D01*
X636603Y-326531D01*
X636658Y-326513D01*
X636721Y-326487D01*
X636784Y-326450D01*
X636843Y-326398D01*
X636851Y-326391D01*
X636865Y-326372D01*
X636891Y-326339D01*
X636921Y-326294D01*
X636947Y-326239D01*
X636973Y-326172D01*
X636987Y-326098D01*
X636995Y-326017D01*
Y-325995D01*
X636991Y-325980D01*
X636987Y-325939D01*
X636976Y-325887D01*
X636958Y-325828D01*
X636932Y-325769D01*
X636895Y-325706D01*
X636847Y-325651D01*
X636839Y-325643D01*
X636821Y-325628D01*
X636788Y-325606D01*
X636747Y-325580D01*
X636692Y-325551D01*
X636629Y-325528D01*
X636558Y-325514D01*
X636481Y-325506D01*
D02*
G37*
G36*
X656685Y-323176D02*
X654732D01*
Y-323782D01*
X654736Y-323808D01*
X654739Y-323864D01*
X654743Y-323927D01*
X654750Y-323993D01*
X654761Y-324060D01*
X654776Y-324115D01*
X654780Y-324123D01*
X654784Y-324141D01*
X654795Y-324167D01*
X654810Y-324201D01*
X654832Y-324237D01*
X654854Y-324274D01*
X654880Y-324311D01*
X654909Y-324348D01*
X654917Y-324352D01*
X654932Y-324367D01*
X654957Y-324389D01*
X654994Y-324415D01*
X655043Y-324445D01*
X655098Y-324478D01*
X655161Y-324507D01*
X655231Y-324533D01*
X655235D01*
X655242Y-324537D01*
X655254Y-324541D01*
X655268Y-324545D01*
X655287Y-324548D01*
X655313Y-324556D01*
X655339Y-324563D01*
X655368Y-324570D01*
X655442Y-324582D01*
X655527Y-324593D01*
X655623Y-324600D01*
X655727Y-324604D01*
X655731D01*
X655746D01*
X655764D01*
X655794Y-324600D01*
X655827D01*
X655864Y-324596D01*
X655908Y-324593D01*
X655953Y-324589D01*
X656053Y-324570D01*
X656156Y-324548D01*
X656252Y-324515D01*
X656301Y-324493D01*
X656341Y-324471D01*
X656345D01*
X656352Y-324463D01*
X656363Y-324456D01*
X656378Y-324448D01*
X656415Y-324419D01*
X656460Y-324382D01*
X656508Y-324334D01*
X656556Y-324278D01*
X656597Y-324215D01*
X656630Y-324149D01*
X656634Y-324141D01*
X656637Y-324123D01*
X656648Y-324089D01*
X656660Y-324041D01*
X656667Y-323982D01*
X656678Y-323908D01*
X656682Y-323864D01*
Y-323816D01*
X656685Y-323767D01*
Y-323176D01*
D02*
G37*
G36*
X147381Y-347242D02*
X146574Y-348389D01*
X147381D01*
Y-347242D01*
D02*
G37*
G36*
X143081Y-347017D02*
X142275D01*
Y-347864D01*
X143037D01*
X143081Y-347860D01*
X143133Y-347856D01*
X143192Y-347853D01*
X143251Y-347845D01*
X143311Y-347834D01*
X143362Y-347819D01*
X143370Y-347816D01*
X143385Y-347808D01*
X143407Y-347797D01*
X143436Y-347782D01*
X143470Y-347760D01*
X143503Y-347734D01*
X143536Y-347701D01*
X143562Y-347664D01*
X143566Y-347660D01*
X143573Y-347645D01*
X143584Y-347623D01*
X143599Y-347594D01*
X143610Y-347560D01*
X143621Y-347523D01*
X143629Y-347479D01*
X143632Y-347435D01*
Y-347431D01*
Y-347427D01*
X143629Y-347405D01*
X143625Y-347372D01*
X143618Y-347327D01*
X143599Y-347283D01*
X143577Y-347231D01*
X143544Y-347183D01*
X143499Y-347135D01*
X143492Y-347131D01*
X143473Y-347116D01*
X143444Y-347098D01*
X143396Y-347076D01*
X143340Y-347054D01*
X143266Y-347035D01*
X143181Y-347020D01*
X143081Y-347017D01*
D02*
G37*
G36*
X207210Y-378156D02*
X206064D01*
Y-378963D01*
X207210Y-378156D01*
D02*
G37*
G36*
Y-380147D02*
X206064D01*
Y-380953D01*
X207210Y-380147D01*
D02*
G37*
G36*
X210459Y-368377D02*
X209312D01*
Y-369184D01*
X210459Y-368377D01*
D02*
G37*
G36*
X217897Y-377810D02*
X217882D01*
X217875D01*
X217871D01*
X217771Y-377818D01*
X217686Y-377832D01*
X217612Y-377855D01*
X217549Y-377881D01*
X217501Y-377910D01*
X217464Y-377932D01*
X217442Y-377947D01*
X217438Y-377955D01*
X217435D01*
X217405Y-377980D01*
X217383Y-378010D01*
X217342Y-378069D01*
X217316Y-378128D01*
X217294Y-378180D01*
X217283Y-378228D01*
X217279Y-378265D01*
X217275Y-378280D01*
Y-378299D01*
X217279Y-378350D01*
X217286Y-378398D01*
X217301Y-378443D01*
X217316Y-378480D01*
X217327Y-378513D01*
X217342Y-378539D01*
X217349Y-378554D01*
X217353Y-378561D01*
X217386Y-378606D01*
X217420Y-378643D01*
X217460Y-378676D01*
X217494Y-378702D01*
X217527Y-378724D01*
X217553Y-378739D01*
X217571Y-378750D01*
X217579Y-378754D01*
X217634Y-378776D01*
X217690Y-378791D01*
X217742Y-378805D01*
X217790Y-378813D01*
X217830Y-378817D01*
X217864Y-378820D01*
X217882D01*
X217890D01*
X217978Y-378813D01*
X218056Y-378798D01*
X218126Y-378772D01*
X218182Y-378746D01*
X218230Y-378720D01*
X218263Y-378695D01*
X218282Y-378680D01*
X218289Y-378672D01*
X218341Y-378613D01*
X218378Y-378554D01*
X218408Y-378491D01*
X218426Y-378435D01*
X218437Y-378384D01*
X218441Y-378347D01*
X218444Y-378332D01*
Y-378310D01*
X218437Y-378232D01*
X218419Y-378162D01*
X218396Y-378102D01*
X218367Y-378051D01*
X218337Y-378010D01*
X218315Y-377980D01*
X218297Y-377962D01*
X218289Y-377955D01*
X218226Y-377906D01*
X218160Y-377869D01*
X218089Y-377843D01*
X218023Y-377829D01*
X217964Y-377818D01*
X217938Y-377814D01*
X217916D01*
X217897Y-377810D01*
D02*
G37*
G36*
X219111Y-380152D02*
X217964D01*
Y-380959D01*
X219111Y-380152D01*
D02*
G37*
G36*
X222659Y-368349D02*
X221512D01*
Y-369156D01*
X222659Y-368349D01*
D02*
G37*
G36*
X237841Y-366113D02*
X237819D01*
X237815D01*
X237811D01*
X237752Y-366116D01*
X237697Y-366131D01*
X237649Y-366150D01*
X237608Y-366172D01*
X237575Y-366194D01*
X237552Y-366213D01*
X237534Y-366227D01*
X237530Y-366231D01*
X237493Y-366276D01*
X237464Y-366327D01*
X237445Y-366375D01*
X237430Y-366424D01*
X237423Y-366468D01*
X237419Y-366501D01*
X237416Y-366523D01*
Y-366531D01*
X237419Y-366597D01*
X237434Y-366657D01*
X237453Y-366708D01*
X237475Y-366753D01*
X237493Y-366786D01*
X237512Y-366812D01*
X237526Y-366830D01*
X237530Y-366834D01*
X237575Y-366871D01*
X237626Y-366901D01*
X237674Y-366919D01*
X237723Y-366934D01*
X237763Y-366941D01*
X237797Y-366945D01*
X237819Y-366949D01*
X237823D01*
X237826D01*
X237885Y-366945D01*
X237937Y-366930D01*
X237985Y-366912D01*
X238026Y-366890D01*
X238059Y-366871D01*
X238085Y-366853D01*
X238100Y-366838D01*
X238104Y-366834D01*
X238144Y-366786D01*
X238174Y-366738D01*
X238193Y-366686D01*
X238207Y-366638D01*
X238215Y-366594D01*
X238222Y-366560D01*
Y-366531D01*
X238218Y-366468D01*
X238204Y-366409D01*
X238185Y-366361D01*
X238163Y-366316D01*
X238141Y-366283D01*
X238122Y-366257D01*
X238107Y-366238D01*
X238104Y-366235D01*
X238056Y-366194D01*
X238007Y-366164D01*
X237959Y-366142D01*
X237915Y-366127D01*
X237874Y-366120D01*
X237841Y-366113D01*
D02*
G37*
G36*
X236657Y-366009D02*
X236646D01*
X236638D01*
X236635D01*
X236557Y-366017D01*
X236483Y-366031D01*
X236420Y-366057D01*
X236368Y-366083D01*
X236328Y-366109D01*
X236294Y-366135D01*
X236276Y-366150D01*
X236268Y-366157D01*
X236220Y-366216D01*
X236183Y-366276D01*
X236161Y-366338D01*
X236143Y-366398D01*
X236132Y-366449D01*
X236128Y-366494D01*
X236124Y-366509D01*
Y-366531D01*
X236128Y-366583D01*
X236135Y-366634D01*
X236146Y-366683D01*
X236157Y-366723D01*
X236169Y-366757D01*
X236180Y-366782D01*
X236187Y-366797D01*
X236191Y-366805D01*
X236220Y-366849D01*
X236250Y-366886D01*
X236283Y-366919D01*
X236317Y-366945D01*
X236343Y-366967D01*
X236365Y-366982D01*
X236383Y-366990D01*
X236387Y-366993D01*
X236435Y-367012D01*
X236479Y-367027D01*
X236524Y-367038D01*
X236564Y-367045D01*
X236598Y-367049D01*
X236624Y-367053D01*
X236638D01*
X236646D01*
X236724Y-367045D01*
X236794Y-367030D01*
X236857Y-367008D01*
X236912Y-366979D01*
X236953Y-366953D01*
X236986Y-366930D01*
X237005Y-366916D01*
X237012Y-366908D01*
X237060Y-366853D01*
X237097Y-366790D01*
X237123Y-366731D01*
X237142Y-366671D01*
X237153Y-366620D01*
X237157Y-366579D01*
X237160Y-366564D01*
Y-366542D01*
X237153Y-366460D01*
X237138Y-366387D01*
X237112Y-366320D01*
X237086Y-366264D01*
X237057Y-366220D01*
X237031Y-366187D01*
X237016Y-366168D01*
X237009Y-366161D01*
X236949Y-366109D01*
X236886Y-366072D01*
X236824Y-366046D01*
X236768Y-366028D01*
X236713Y-366017D01*
X236672Y-366013D01*
X236657Y-366009D01*
D02*
G37*
G36*
X237959Y-368355D02*
X236812D01*
Y-369162D01*
X237959Y-368355D01*
D02*
G37*
G36*
X241656Y-366035D02*
X241641D01*
X241634D01*
X241630D01*
X241534Y-366042D01*
X241449Y-366057D01*
X241378Y-366079D01*
X241319Y-366105D01*
X241271Y-366135D01*
X241238Y-366157D01*
X241216Y-366172D01*
X241208Y-366179D01*
X241157Y-366235D01*
X241120Y-366294D01*
X241094Y-366353D01*
X241075Y-366412D01*
X241064Y-366460D01*
X241060Y-366501D01*
X241057Y-366516D01*
Y-366538D01*
X241064Y-366616D01*
X241079Y-366686D01*
X241105Y-366749D01*
X241134Y-366805D01*
X241160Y-366845D01*
X241186Y-366879D01*
X241201Y-366897D01*
X241208Y-366904D01*
X241267Y-366953D01*
X241334Y-366990D01*
X241401Y-367012D01*
X241464Y-367030D01*
X241519Y-367041D01*
X241541Y-367045D01*
X241564D01*
X241582Y-367049D01*
X241593D01*
X241600D01*
X241604D01*
X241700Y-367041D01*
X241789Y-367027D01*
X241867Y-367001D01*
X241930Y-366971D01*
X241982Y-366945D01*
X242019Y-366919D01*
X242030Y-366912D01*
X242041Y-366904D01*
X242044Y-366897D01*
X242048D01*
X242078Y-366867D01*
X242107Y-366838D01*
X242148Y-366775D01*
X242181Y-366712D01*
X242200Y-366653D01*
X242215Y-366605D01*
X242218Y-366564D01*
X242222Y-366549D01*
Y-366490D01*
X242215Y-366453D01*
X242196Y-366387D01*
X242170Y-366327D01*
X242144Y-366276D01*
X242115Y-366235D01*
X242089Y-366205D01*
X242070Y-366187D01*
X242067Y-366179D01*
X242063D01*
X242000Y-366131D01*
X241930Y-366094D01*
X241856Y-366068D01*
X241786Y-366054D01*
X241726Y-366042D01*
X241700Y-366039D01*
X241674D01*
X241656Y-366035D01*
D02*
G37*
G36*
X241959Y-368355D02*
X240812D01*
Y-369162D01*
X241959Y-368355D01*
D02*
G37*
G36*
X252730Y-366003D02*
X252697D01*
X252679D01*
X252675D01*
X252671D01*
X252557D01*
X252453Y-366011D01*
X252361Y-366018D01*
X252272Y-366026D01*
X252198Y-366037D01*
X252127Y-366052D01*
X252068Y-366066D01*
X252013Y-366077D01*
X251968Y-366092D01*
X251931Y-366107D01*
X251898Y-366118D01*
X251872Y-366133D01*
X251854Y-366140D01*
X251842Y-366148D01*
X251835Y-366155D01*
X251831D01*
X251795Y-366185D01*
X251765Y-366214D01*
X251735Y-366244D01*
X251713Y-366274D01*
X251676Y-366336D01*
X251650Y-366392D01*
X251635Y-366444D01*
X251628Y-366481D01*
X251624Y-366496D01*
Y-366518D01*
X251628Y-366559D01*
X251632Y-366596D01*
X251658Y-366666D01*
X251691Y-366729D01*
X251728Y-366784D01*
X251765Y-366825D01*
X251798Y-366858D01*
X251824Y-366877D01*
X251828Y-366884D01*
X251831D01*
X251876Y-366910D01*
X251928Y-366932D01*
X251987Y-366954D01*
X252050Y-366969D01*
X252116Y-366984D01*
X252187Y-366995D01*
X252331Y-367014D01*
X252398Y-367021D01*
X252460Y-367025D01*
X252520Y-367028D01*
X252568D01*
X252612Y-367032D01*
X252645D01*
X252664D01*
X252671D01*
X252786Y-367028D01*
X252890Y-367025D01*
X252986Y-367017D01*
X253075Y-367006D01*
X253152Y-366995D01*
X253223Y-366980D01*
X253286Y-366966D01*
X253341Y-366951D01*
X253389Y-366936D01*
X253430Y-366925D01*
X253463Y-366910D01*
X253493Y-366899D01*
X253511Y-366888D01*
X253526Y-366880D01*
X253533Y-366873D01*
X253537D01*
X253570Y-366847D01*
X253600Y-366821D01*
X253622Y-366792D01*
X253644Y-366762D01*
X253678Y-366703D01*
X253700Y-366647D01*
X253711Y-366599D01*
X253718Y-366559D01*
X253722Y-366544D01*
Y-366522D01*
X253718Y-366481D01*
X253715Y-366440D01*
X253704Y-366403D01*
X253689Y-366370D01*
X253656Y-366307D01*
X253619Y-366251D01*
X253578Y-366211D01*
X253544Y-366177D01*
X253530Y-366166D01*
X253519Y-366159D01*
X253515Y-366151D01*
X253511D01*
X253467Y-366126D01*
X253415Y-366103D01*
X253356Y-366081D01*
X253293Y-366066D01*
X253226Y-366052D01*
X253156Y-366040D01*
X253015Y-366022D01*
X252945Y-366015D01*
X252882Y-366011D01*
X252823Y-366007D01*
X252775D01*
X252730Y-366003D01*
D02*
G37*
G36*
X116132Y-263774D02*
X115370D01*
X115325Y-263778D01*
X115273Y-263781D01*
X115214Y-263785D01*
X115155Y-263792D01*
X115096Y-263804D01*
X115044Y-263818D01*
X115037Y-263822D01*
X115022Y-263829D01*
X114999Y-263841D01*
X114970Y-263855D01*
X114937Y-263878D01*
X114903Y-263903D01*
X114870Y-263937D01*
X114844Y-263974D01*
X114840Y-263978D01*
X114833Y-263992D01*
X114822Y-264015D01*
X114807Y-264044D01*
X114796Y-264077D01*
X114785Y-264114D01*
X114778Y-264159D01*
X114774Y-264203D01*
Y-264207D01*
Y-264211D01*
X114778Y-264233D01*
X114781Y-264266D01*
X114789Y-264311D01*
X114807Y-264355D01*
X114829Y-264407D01*
X114863Y-264455D01*
X114907Y-264503D01*
X114915Y-264507D01*
X114933Y-264521D01*
X114963Y-264540D01*
X115011Y-264562D01*
X115066Y-264584D01*
X115140Y-264603D01*
X115225Y-264618D01*
X115325Y-264621D01*
X116132D01*
Y-263774D01*
D02*
G37*
G36*
X143065Y-342619D02*
X142258D01*
Y-343466D01*
X143020D01*
X143065Y-343463D01*
X143116Y-343459D01*
X143176Y-343455D01*
X143235Y-343448D01*
X143294Y-343437D01*
X143346Y-343422D01*
X143353Y-343418D01*
X143368Y-343411D01*
X143390Y-343400D01*
X143420Y-343385D01*
X143453Y-343363D01*
X143486Y-343337D01*
X143520Y-343304D01*
X143546Y-343267D01*
X143549Y-343263D01*
X143557Y-343248D01*
X143568Y-343226D01*
X143583Y-343196D01*
X143594Y-343163D01*
X143605Y-343126D01*
X143612Y-343082D01*
X143616Y-343037D01*
Y-343034D01*
Y-343030D01*
X143612Y-343008D01*
X143608Y-342974D01*
X143601Y-342930D01*
X143583Y-342886D01*
X143560Y-342834D01*
X143527Y-342786D01*
X143483Y-342738D01*
X143475Y-342734D01*
X143457Y-342719D01*
X143427Y-342701D01*
X143379Y-342678D01*
X143324Y-342656D01*
X143250Y-342638D01*
X143165Y-342623D01*
X143065Y-342619D01*
D02*
G37*
%LPD*%
D15*
X547126Y-343543D02*
G03*
X547126Y-343543I-394J0D01*
G01*
X-20374Y-188583D02*
Y-175984D01*
X-16437D01*
Y-188583D02*
Y-175984D01*
X-20374Y-188583D02*
X-16437D01*
X-20374Y-241339D02*
Y-228740D01*
X-16437D01*
Y-241339D02*
Y-228740D01*
X-20374Y-241339D02*
X-16437D01*
X-20374Y-294882D02*
Y-282283D01*
X-16437D01*
Y-294882D02*
Y-282283D01*
X-20374Y-294882D02*
X-16437D01*
X-20374Y-347638D02*
Y-335039D01*
X-16437D01*
Y-347638D02*
Y-335039D01*
X-20374Y-347638D02*
X-16437D01*
X-20374Y-114764D02*
Y-102165D01*
X-16437D01*
Y-114764D02*
Y-102165D01*
X-20374Y-114764D02*
X-16437D01*
X-20374Y-71457D02*
Y-58858D01*
X-16437D01*
Y-71457D02*
Y-58858D01*
X-20374Y-71457D02*
X-16437D01*
D16*
X99016Y-119685D02*
G03*
X99016Y-119685I-1969J0D01*
G01*
X286614Y-115147D02*
G03*
X286614Y-115147I-1969J0D01*
G01*
X216142Y-115600D02*
G03*
X216142Y-115600I-1969J0D01*
G01*
X80709Y-129528D02*
X84646D01*
X80709Y-122441D02*
X84646D01*
X80709Y-129528D02*
Y-122441D01*
X84646Y-129528D02*
Y-122441D01*
X65650Y-114862D02*
Y-112697D01*
X69784Y-114862D02*
Y-112697D01*
X65650D02*
X69784D01*
X65650Y-114862D02*
X69784D01*
X65650Y-111319D02*
Y-109153D01*
X69784Y-111319D02*
Y-109153D01*
X65650D02*
X69784D01*
X65650Y-111319D02*
X69784D01*
Y-118799D02*
Y-116634D01*
X65650Y-118799D02*
Y-116634D01*
Y-118799D02*
X69784D01*
X65650Y-116634D02*
X69784D01*
X661516Y-83169D02*
Y-79035D01*
X663681Y-83169D02*
Y-79035D01*
X661516Y-83169D02*
X663681D01*
X661516Y-79035D02*
X663681D01*
X674508Y-80413D02*
Y-76279D01*
X676673Y-80413D02*
Y-76279D01*
X674508Y-80413D02*
X676673D01*
X674508Y-76279D02*
X676673D01*
X548327Y-271949D02*
X552461D01*
X548327Y-269783D02*
X552461D01*
Y-271949D02*
Y-269783D01*
X548327Y-271949D02*
Y-269783D01*
X607972Y-82972D02*
Y-80807D01*
X612106Y-82972D02*
Y-80807D01*
X607972D02*
X612106D01*
X607972Y-82972D02*
X612106D01*
X604232Y-102264D02*
Y-100098D01*
X608366Y-102264D02*
Y-100098D01*
X604232D02*
X608366D01*
X604232Y-102264D02*
X608366D01*
X581398Y-81791D02*
Y-79626D01*
X585532Y-81791D02*
Y-79626D01*
X581398D02*
X585532D01*
X581398Y-81791D02*
X585532D01*
X573721Y-107382D02*
Y-105217D01*
X577854Y-107382D02*
Y-105217D01*
X573721D02*
X577854D01*
X573721Y-107382D02*
X577854D01*
X233957Y-117421D02*
X236122D01*
X233957Y-113287D02*
X236122D01*
X233957Y-117421D02*
Y-113287D01*
X236122Y-117421D02*
Y-113287D01*
X241043Y-123524D02*
Y-121358D01*
X236910Y-123524D02*
Y-121358D01*
Y-123524D02*
X241043D01*
X236910Y-121358D02*
X241043D01*
X259941Y-105807D02*
Y-103642D01*
X255807Y-105807D02*
Y-103642D01*
Y-105807D02*
X259941D01*
X255807Y-103642D02*
X259941D01*
X258760Y-118405D02*
X260925D01*
X258760Y-122539D02*
X260925D01*
Y-118405D01*
X258760Y-122539D02*
Y-118405D01*
X163091Y-111319D02*
X169980D01*
X163091Y-107579D02*
X169980D01*
Y-111319D02*
Y-107579D01*
X163091Y-111319D02*
Y-107579D01*
X265748Y-120669D02*
Y-117126D01*
X272441Y-120669D02*
Y-117126D01*
X265748D02*
X272441D01*
X265748Y-120669D02*
X272441D01*
X233465Y-110236D02*
X240551D01*
X233465Y-106299D02*
X240551D01*
Y-110236D02*
Y-106299D01*
X233465Y-110236D02*
Y-106299D01*
X670177Y-83169D02*
X672342D01*
X670177Y-79035D02*
X672342D01*
X670177Y-83169D02*
Y-79035D01*
X672342Y-83169D02*
Y-79035D01*
X677461Y-68799D02*
Y-66634D01*
X681595Y-68799D02*
Y-66634D01*
X677461D02*
X681595D01*
X677461Y-68799D02*
X681595D01*
X629626Y-87697D02*
Y-85532D01*
X625492Y-87697D02*
Y-85532D01*
Y-87697D02*
X629626D01*
X625492Y-85532D02*
X629626D01*
X604626Y-90847D02*
Y-88681D01*
X608760Y-90847D02*
Y-88681D01*
X604626D02*
X608760D01*
X604626Y-90847D02*
X608760D01*
X630020Y-100689D02*
Y-98524D01*
X625886Y-100689D02*
Y-98524D01*
Y-100689D02*
X630020D01*
X625886Y-98524D02*
X630020D01*
X604626Y-96358D02*
Y-94193D01*
X608760Y-96358D02*
Y-94193D01*
X604626D02*
X608760D01*
X604626Y-96358D02*
X608760D01*
X593012Y-82972D02*
X595177D01*
X593012Y-87106D02*
X595177D01*
Y-82972D01*
X593012Y-87106D02*
Y-82972D01*
X440256Y-112106D02*
Y-109941D01*
X436122Y-112106D02*
Y-109941D01*
Y-112106D02*
X440256D01*
X436122Y-109941D02*
X440256D01*
X406102Y-111713D02*
Y-109547D01*
X410236Y-111713D02*
Y-109547D01*
X406102D02*
X410236D01*
X406102Y-111713D02*
X410236D01*
X571949Y-89272D02*
Y-87106D01*
X576083Y-89272D02*
Y-87106D01*
X571949D02*
X576083D01*
X571949Y-89272D02*
X576083D01*
X596555Y-99114D02*
Y-96949D01*
X592421Y-99114D02*
Y-96949D01*
Y-99114D02*
X596555D01*
X592421Y-96949D02*
X596555D01*
X571555Y-101476D02*
Y-99311D01*
X575689Y-101476D02*
Y-99311D01*
X571555D02*
X575689D01*
X571555Y-101476D02*
X575689D01*
X242028Y-115256D02*
Y-113091D01*
X246161Y-115256D02*
Y-113091D01*
X242028D02*
X246161D01*
X242028Y-115256D02*
X246161D01*
X242028Y-131791D02*
Y-129626D01*
X246161Y-131791D02*
Y-129626D01*
X242028D02*
X246161D01*
X242028Y-131791D02*
X246161D01*
X257579Y-116437D02*
Y-114272D01*
X253445Y-116437D02*
Y-114272D01*
Y-116437D02*
X257579D01*
X253445Y-114272D02*
X257579D01*
X256004Y-131791D02*
Y-129626D01*
X251870Y-131791D02*
Y-129626D01*
Y-131791D02*
X256004D01*
X251870Y-129626D02*
X256004D01*
X666634Y-83169D02*
X668799D01*
X666634Y-79035D02*
X668799D01*
X666634Y-83169D02*
Y-79035D01*
X668799Y-83169D02*
Y-79035D01*
X682382Y-42421D02*
Y-40256D01*
X678248Y-42421D02*
Y-40256D01*
Y-42421D02*
X682382D01*
X678248Y-40256D02*
X682382D01*
X695374Y-44390D02*
X697539D01*
X695374Y-48524D02*
X697539D01*
Y-44390D01*
X695374Y-48524D02*
Y-44390D01*
X548032Y-267126D02*
Y-264764D01*
X552362Y-267126D02*
Y-264764D01*
X548032D02*
X552362D01*
X548032Y-267126D02*
X552362D01*
X637303Y-212697D02*
X644587D01*
X637303Y-199114D02*
X644587D01*
X637303Y-212697D02*
Y-199114D01*
X644587Y-212697D02*
Y-199114D01*
X614862Y-240846D02*
Y-238681D01*
X618996Y-240846D02*
Y-238681D01*
X614862D02*
X618996D01*
X614862Y-240846D02*
X618996D01*
X566634Y-219980D02*
X568799D01*
X566634Y-224114D02*
X568799D01*
Y-219980D01*
X566634Y-224114D02*
Y-219980D01*
X593307Y-232087D02*
X595669D01*
X593307Y-227756D02*
X595669D01*
X593307Y-232087D02*
Y-227756D01*
X595669Y-232087D02*
Y-227756D01*
X608760Y-233366D02*
Y-231201D01*
X604626Y-233366D02*
Y-231201D01*
Y-233366D02*
X608760D01*
X604626Y-231201D02*
X608760D01*
X666634Y-245768D02*
Y-241634D01*
X668799Y-245768D02*
Y-241634D01*
X666634Y-245768D02*
X668799D01*
X666634Y-241634D02*
X668799D01*
X671555Y-241043D02*
X675689D01*
X671555Y-243209D02*
X675689D01*
X671555D02*
Y-241043D01*
X675689Y-243209D02*
Y-241043D01*
X598130Y-231988D02*
X600295D01*
X598130Y-227854D02*
X600295D01*
X598130Y-231988D02*
Y-227854D01*
X600295Y-231988D02*
Y-227854D01*
X644882Y-227756D02*
Y-223425D01*
X642520Y-227756D02*
Y-223425D01*
X644882D01*
X642520Y-227756D02*
X644882D01*
X565059Y-201673D02*
X567224D01*
X565059Y-197539D02*
X567224D01*
X565059Y-201673D02*
Y-197539D01*
X567224Y-201673D02*
Y-197539D01*
X549902Y-201476D02*
Y-199311D01*
X554035Y-201476D02*
Y-199311D01*
X549902D02*
X554035D01*
X549902Y-201476D02*
X554035D01*
X553642Y-211319D02*
X555807D01*
X553642Y-215453D02*
X555807D01*
Y-211319D01*
X553642Y-215453D02*
Y-211319D01*
X560925Y-206594D02*
Y-204429D01*
X565059Y-206594D02*
Y-204429D01*
X560925D02*
X565059D01*
X560925Y-206594D02*
X565059D01*
X560925Y-210138D02*
Y-207972D01*
X565059Y-210138D02*
Y-207972D01*
X560925D02*
X565059D01*
X560925Y-210138D02*
X565059D01*
X549902Y-107973D02*
X554035D01*
X549902Y-110138D02*
X554035D01*
X549902D02*
Y-107973D01*
X554035Y-110138D02*
Y-107973D01*
X562106Y-110531D02*
X566240D01*
X562106Y-108366D02*
X566240D01*
Y-110531D02*
Y-108366D01*
X562106Y-110531D02*
Y-108366D01*
X548327Y-275886D02*
Y-273721D01*
X552461Y-275886D02*
Y-273721D01*
X548327D02*
X552461D01*
X548327Y-275886D02*
X552461D01*
X606791Y-293209D02*
X608957D01*
X606791Y-297342D02*
X608957D01*
Y-293209D01*
X606791Y-297342D02*
Y-293209D01*
X558563Y-287697D02*
Y-285531D01*
X562697Y-287697D02*
Y-285531D01*
X558563D02*
X562697D01*
X558563Y-287697D02*
X562697D01*
X581398Y-290846D02*
Y-288681D01*
X585532Y-290846D02*
Y-288681D01*
X581398D02*
X585532D01*
X581398Y-290846D02*
X585532D01*
X632579Y-272933D02*
Y-265650D01*
X646161Y-272933D02*
Y-265650D01*
X632579D02*
X646161D01*
X632579Y-272933D02*
X646161D01*
X592913Y-286024D02*
X595276D01*
X592913Y-281693D02*
X595276D01*
X592913Y-286024D02*
Y-281693D01*
X595276Y-286024D02*
Y-281693D01*
X548032Y-286122D02*
Y-283957D01*
X552165Y-286122D02*
Y-283957D01*
X548032D02*
X552165D01*
X548032Y-286122D02*
X552165D01*
X581398Y-286516D02*
Y-284350D01*
X585532Y-286516D02*
Y-284350D01*
X581398D02*
X585532D01*
X581398Y-286516D02*
X585532D01*
X551870Y-261713D02*
X554035D01*
X551870Y-257579D02*
X554035D01*
X551870Y-261713D02*
Y-257579D01*
X554035Y-261713D02*
Y-257579D01*
X662402Y-281890D02*
X666732D01*
X662402Y-284252D02*
X666732D01*
X662402D02*
Y-281890D01*
X666732Y-284252D02*
Y-281890D01*
X680217Y-303051D02*
X684350D01*
X680217Y-300886D02*
X684350D01*
Y-303051D02*
Y-300886D01*
X680217Y-303051D02*
Y-300886D01*
Y-307382D02*
X684350D01*
X680217Y-305217D02*
X684350D01*
Y-307382D02*
Y-305217D01*
X680217Y-307382D02*
Y-305217D01*
X573130Y-152067D02*
X580413D01*
X573130Y-138484D02*
X580413D01*
X573130Y-152067D02*
Y-138484D01*
X580413Y-152067D02*
Y-138484D01*
X532087Y-142520D02*
X536417D01*
X532087Y-140157D02*
X536417D01*
Y-142520D02*
Y-140157D01*
X532087Y-142520D02*
Y-140157D01*
X495866D02*
X500197D01*
X495866Y-142520D02*
X500197D01*
X495866D02*
Y-140157D01*
X500197Y-142520D02*
Y-140157D01*
X495866Y-136221D02*
X500197D01*
X495866Y-138583D02*
X500197D01*
X495866D02*
Y-136221D01*
X500197Y-138583D02*
Y-136221D01*
X503642Y-109350D02*
X505807D01*
X503642Y-113484D02*
X505807D01*
Y-109350D01*
X503642Y-113484D02*
Y-109350D01*
X507579D02*
X509744D01*
X507579Y-113484D02*
X509744D01*
Y-109350D01*
X507579Y-113484D02*
Y-109350D01*
X472539Y-124114D02*
X474705D01*
X472539Y-119980D02*
X474705D01*
X472539Y-124114D02*
Y-119980D01*
X474705Y-124114D02*
Y-119980D01*
X493799Y-110138D02*
Y-107973D01*
X489665Y-110138D02*
Y-107973D01*
Y-110138D02*
X493799D01*
X489665Y-107973D02*
X493799D01*
X474114Y-118012D02*
Y-115847D01*
X469980Y-118012D02*
Y-115847D01*
Y-118012D02*
X474114D01*
X469980Y-115847D02*
X474114D01*
X487106Y-110138D02*
Y-107973D01*
X482972Y-110138D02*
Y-107973D01*
Y-110138D02*
X487106D01*
X482972Y-107973D02*
X487106D01*
X506398Y-120768D02*
Y-118602D01*
X502264Y-120768D02*
Y-118602D01*
Y-120768D02*
X506398D01*
X502264Y-118602D02*
X506398D01*
X472342Y-135728D02*
Y-133563D01*
X476476Y-135728D02*
Y-133563D01*
X472342D02*
X476476D01*
X472342Y-135728D02*
X476476D01*
X503937Y-127756D02*
Y-123425D01*
X501575Y-127756D02*
Y-123425D01*
X503937D01*
X501575Y-127756D02*
X503937D01*
X501772Y-132283D02*
X506102D01*
X501772Y-134646D02*
X506102D01*
X501772D02*
Y-132283D01*
X506102Y-134646D02*
Y-132283D01*
X476279Y-110138D02*
X480413D01*
X476279Y-107972D02*
X480413D01*
Y-110138D02*
Y-107972D01*
X476279Y-110138D02*
Y-107972D01*
X53937Y-43307D02*
Y-36220D01*
X57874Y-43307D02*
Y-36220D01*
X53937Y-43307D02*
X57874D01*
X53937Y-36220D02*
X57874D01*
X109449Y-44094D02*
Y-37008D01*
X113386Y-44094D02*
Y-37008D01*
X109449Y-44094D02*
X113386D01*
X109449Y-37008D02*
X113386D01*
X664567Y-45276D02*
X671654D01*
X664567Y-49213D02*
X671654D01*
X664567D02*
Y-45276D01*
X671654Y-49213D02*
Y-45276D01*
X601968Y-46850D02*
X609055D01*
X601968Y-42913D02*
X609055D01*
Y-46850D02*
Y-42913D01*
X601968Y-46850D02*
Y-42913D01*
X422736Y-184941D02*
X426870D01*
X422736Y-182776D02*
X426870D01*
Y-184941D02*
Y-182776D01*
X422736Y-184941D02*
Y-182776D01*
X139075Y-131595D02*
Y-127461D01*
X141240Y-131595D02*
Y-127461D01*
X139075Y-131595D02*
X141240D01*
X139075Y-127461D02*
X141240D01*
X135748Y-125079D02*
Y-115079D01*
X187244D01*
Y-125079D02*
Y-115079D01*
X135748Y-125079D02*
X187244D01*
X358804Y-116142D02*
X371796D01*
X358804Y-109055D02*
X371796D01*
Y-116142D02*
Y-109055D01*
X358804Y-116142D02*
Y-109055D01*
Y-139764D02*
Y-132677D01*
X371796Y-139764D02*
Y-132677D01*
X358804D02*
X371796D01*
X358804Y-139764D02*
X371796D01*
X566142Y-116929D02*
X570079D01*
X566142Y-124016D02*
X570079D01*
Y-116929D01*
X566142Y-124016D02*
Y-116929D01*
X601772Y-171260D02*
Y-164173D01*
X588779Y-171260D02*
Y-164173D01*
Y-171260D02*
X601772D01*
X588779Y-164173D02*
X601772D01*
X358804Y-128347D02*
Y-121260D01*
X371796Y-128347D02*
Y-121260D01*
X358804D02*
X371796D01*
X358804Y-128347D02*
X371796D01*
X549291Y-348287D02*
X629291D01*
Y-311791D01*
X549291D02*
X629291D01*
X549291Y-348287D02*
Y-311791D01*
X5315Y-330561D02*
Y-303002D01*
X-22244D02*
X5315D01*
X-22244Y-330561D02*
X5315D01*
X-22244D02*
Y-303002D01*
X5315Y-277410D02*
Y-249850D01*
X-22244D02*
X5315D01*
X-22244Y-277410D02*
X5315D01*
X-22244D02*
Y-249850D01*
X5315Y-224260D02*
Y-196701D01*
X-22244D02*
X5315D01*
X-22244Y-224260D02*
X5315D01*
X-22244D02*
Y-196701D01*
X5315Y-171112D02*
Y-143553D01*
X-22244D02*
X5315D01*
X-22244Y-171112D02*
X5315D01*
X-22244D02*
Y-143553D01*
X71260Y-216535D02*
X80315D01*
X71260D02*
Y-208661D01*
X80315D01*
Y-216535D02*
Y-208661D01*
X78347Y-216535D02*
X80315Y-214567D01*
X70276Y-163386D02*
X79331D01*
X70276D02*
Y-155512D01*
X79331D01*
Y-163386D02*
Y-155512D01*
X77362Y-163386D02*
X79331Y-161417D01*
X45374Y-5413D02*
X49114D01*
X45374Y1476D02*
X49114D01*
X45374Y-5413D02*
Y1476D01*
X49114Y-5413D02*
Y1476D01*
X38484Y-5413D02*
X42224D01*
X38484Y1476D02*
X42224D01*
X38484Y-5413D02*
Y1476D01*
X42224Y-5413D02*
Y1476D01*
X31594Y-5413D02*
X35335D01*
X31594Y1476D02*
X35335D01*
X31594Y-5413D02*
Y1476D01*
X35335Y-5413D02*
Y1476D01*
X24705Y-5413D02*
X28445D01*
X24705Y1476D02*
X28445D01*
X24705Y-5413D02*
Y1476D01*
X28445Y-5413D02*
Y1476D01*
X93504Y-135827D02*
Y-116142D01*
X113189Y-135827D02*
Y-116142D01*
X93504D02*
X113189D01*
X93504Y-135827D02*
X113189D01*
X76279Y-137697D02*
X83169D01*
X76279Y-133957D02*
X83169D01*
Y-137697D02*
Y-133957D01*
X76279Y-137697D02*
Y-133957D01*
X71260Y-268701D02*
X80315D01*
X71260D02*
Y-260827D01*
X80315D01*
Y-268701D02*
Y-260827D01*
X78347Y-268701D02*
X80315Y-266732D01*
X39173Y-267913D02*
X49409D01*
X39173D02*
Y-257677D01*
X49409D01*
Y-267913D02*
Y-257677D01*
X39173Y-162598D02*
X49409D01*
X39173D02*
Y-152362D01*
X49409D01*
Y-162598D02*
Y-152362D01*
X72933Y-336122D02*
Y-329232D01*
X76673Y-336122D02*
Y-329232D01*
X72933Y-336122D02*
X76673D01*
X72933Y-329232D02*
X76673D01*
X80807Y-336122D02*
Y-329232D01*
X84547Y-336122D02*
Y-329232D01*
X80807Y-336122D02*
X84547D01*
X80807Y-329232D02*
X84547D01*
X70276Y-322835D02*
X79331D01*
X70276D02*
Y-314961D01*
X79331D01*
Y-322835D02*
Y-314961D01*
X77362Y-322835D02*
X79331Y-320866D01*
X39173Y-322047D02*
X49409D01*
X39173D02*
Y-311811D01*
X49409D01*
Y-322047D02*
Y-311811D01*
X39173Y-215748D02*
X49409D01*
X39173D02*
Y-205512D01*
X49409D01*
Y-215748D02*
Y-205512D01*
X60236Y-318701D02*
Y-315158D01*
X53543Y-318701D02*
Y-315158D01*
Y-318701D02*
X60236D01*
X53543Y-315158D02*
X60236D01*
X61417Y-212402D02*
Y-208858D01*
X54724Y-212402D02*
Y-208858D01*
Y-212402D02*
X61417D01*
X54724Y-208858D02*
X61417D01*
Y-264567D02*
Y-261024D01*
X54724Y-264567D02*
Y-261024D01*
Y-264567D02*
X61417D01*
X54724Y-261024D02*
X61417D01*
X73917Y-227854D02*
Y-220965D01*
X77658Y-227854D02*
Y-220965D01*
X73917Y-227854D02*
X77658D01*
X73917Y-220965D02*
X77658D01*
X80807Y-227854D02*
Y-220965D01*
X84547Y-227854D02*
Y-220965D01*
X80807Y-227854D02*
X84547D01*
X80807Y-220965D02*
X84547D01*
X81791Y-281988D02*
Y-275098D01*
X85532Y-281988D02*
Y-275098D01*
X81791Y-281988D02*
X85532D01*
X81791Y-275098D02*
X85532D01*
X73917Y-281988D02*
Y-275098D01*
X77658Y-281988D02*
Y-275098D01*
X73917Y-281988D02*
X77658D01*
X73917Y-275098D02*
X77658D01*
X72933Y-175689D02*
Y-168799D01*
X76673Y-175689D02*
Y-168799D01*
X72933Y-175689D02*
X76673D01*
X72933Y-168799D02*
X76673D01*
X80807Y-175689D02*
Y-168799D01*
X84547Y-175689D02*
Y-168799D01*
X80807Y-175689D02*
X84547D01*
X80807Y-168799D02*
X84547D01*
X462008Y-139517D02*
Y-135777D01*
X455315Y-139517D02*
Y-135777D01*
Y-139517D02*
X462008D01*
X455315Y-135777D02*
X462008D01*
X665354Y-14173D02*
X672441D01*
X665354Y-18110D02*
X672441D01*
X665354D02*
Y-14173D01*
X672441Y-18110D02*
Y-14173D01*
X609223Y-15985D02*
X616310D01*
X609223Y-12049D02*
X616310D01*
Y-15985D02*
Y-12049D01*
X609223Y-15985D02*
Y-12049D01*
X65945Y-336221D02*
Y-329134D01*
X69882Y-336221D02*
Y-329134D01*
X65945Y-336221D02*
X69882D01*
X65945Y-329134D02*
X69882D01*
X197933Y-120226D02*
Y-113730D01*
X201673Y-120226D02*
Y-113730D01*
X197933Y-120226D02*
X201673D01*
X197933Y-113730D02*
X201673D01*
X263583Y-130905D02*
X270276D01*
X263583Y-127362D02*
X270276D01*
Y-130905D02*
Y-127362D01*
X263583Y-130905D02*
Y-127362D01*
X281102Y-131289D02*
Y-111604D01*
X296850Y-131289D02*
Y-111604D01*
X281102D02*
X296850D01*
X281102Y-131289D02*
X296850D01*
X210630Y-131742D02*
Y-112057D01*
X226378Y-131742D02*
Y-112057D01*
X210630D02*
X226378D01*
X210630Y-131742D02*
X226378D01*
X116142Y-80167D02*
Y-73080D01*
X112205Y-80167D02*
Y-73080D01*
X116142D01*
X112205Y-80167D02*
X116142D01*
X100394Y-98868D02*
Y-91781D01*
X96457Y-98868D02*
Y-91781D01*
X100394D01*
X96457Y-98868D02*
X100394D01*
X346137Y-105025D02*
Y-97939D01*
X350075Y-105025D02*
Y-97939D01*
X346137Y-105025D02*
X350075D01*
X346137Y-97939D02*
X350075D01*
X445866Y-129379D02*
Y-122293D01*
X449803Y-129379D02*
Y-122293D01*
X445866Y-129379D02*
X449803D01*
X445866Y-122293D02*
X449803D01*
X263189Y-114025D02*
Y-110088D01*
X270276Y-114025D02*
Y-110088D01*
X263189D02*
X270276D01*
X263189Y-114025D02*
X270276D01*
X65945Y-168701D02*
X69882D01*
X65945Y-175787D02*
X69882D01*
Y-168701D01*
X65945Y-175787D02*
Y-168701D01*
X66929Y-275000D02*
X70866D01*
X66929Y-282087D02*
X70866D01*
Y-275000D01*
X66929Y-282087D02*
Y-275000D01*
X66929Y-220866D02*
X70866D01*
X66929Y-227953D02*
X70866D01*
Y-220866D01*
X66929Y-227953D02*
Y-220866D01*
X519488Y-114025D02*
Y-110088D01*
X512402Y-114025D02*
Y-110088D01*
Y-114025D02*
X519488D01*
X512402Y-110088D02*
X519488D01*
X526575Y-111269D02*
X530512D01*
X526575Y-118356D02*
X530512D01*
Y-111269D01*
X526575Y-118356D02*
Y-111269D01*
X53740Y-155709D02*
X60433D01*
X53740Y-159252D02*
X60433D01*
X53740D02*
Y-155709D01*
X60433Y-159252D02*
Y-155709D01*
X148130Y-111319D02*
Y-107579D01*
X155020Y-111319D02*
Y-107579D01*
X148130D02*
X155020D01*
X148130Y-111319D02*
X155020D01*
D18*
X532225Y-334494D02*
X540887D01*
X532225Y-328982D02*
X540887D01*
Y-334494D02*
Y-328982D01*
X532225Y-334494D02*
Y-328982D01*
X531832Y-350636D02*
X540493D01*
X531832Y-345124D02*
X540493D01*
Y-350636D02*
Y-345124D01*
X531832Y-350636D02*
Y-345124D01*
X652362Y-346850D02*
Y-338189D01*
X657874Y-346850D02*
Y-338189D01*
X652362Y-346850D02*
X657874D01*
X652362Y-338189D02*
X657874D01*
X516969Y-336069D02*
Y-327407D01*
X522285Y-336069D02*
Y-327407D01*
X516969D02*
X522285D01*
X516969Y-336069D02*
X522285D01*
X516871Y-352210D02*
Y-343549D01*
X522186Y-352210D02*
Y-343549D01*
X516871D02*
X522186D01*
X516871Y-352210D02*
X522186D01*
X632677Y-322146D02*
X641339D01*
X632677Y-327461D02*
X641339D01*
Y-322146D01*
X632677Y-327461D02*
Y-322146D01*
X651378Y-322244D02*
X660039D01*
X651378Y-327559D02*
X660039D01*
Y-322244D01*
X651378Y-327559D02*
Y-322244D01*
X634252Y-347244D02*
Y-338583D01*
X639764Y-347244D02*
Y-338583D01*
X634252Y-347244D02*
X639764D01*
X634252Y-338583D02*
X639764D01*
X580413Y-125197D02*
Y-116535D01*
X574705Y-125197D02*
Y-116535D01*
X580413D01*
X574705Y-125197D02*
X580413D01*
X130905Y-348425D02*
X135236D01*
X130905Y-346063D02*
X135236D01*
Y-348425D02*
Y-346063D01*
X130905Y-348425D02*
Y-346063D01*
X598130Y-161319D02*
Y-157579D01*
X591634Y-161319D02*
Y-157579D01*
Y-161319D02*
X598130D01*
X591634Y-157579D02*
X598130D01*
X360335Y-104724D02*
Y-96063D01*
X354626Y-104724D02*
Y-96063D01*
X360335D01*
X354626Y-104724D02*
X360335D01*
X272260Y-382765D02*
X274622D01*
X272260Y-378435D02*
X274622D01*
Y-382765D02*
Y-378435D01*
X272260Y-382765D02*
Y-378435D01*
X205260Y-382765D02*
Y-378435D01*
X207622Y-382765D02*
Y-378435D01*
X205260D02*
X207622D01*
X205260Y-382765D02*
X207622D01*
X209260D02*
X211622D01*
X209260Y-378435D02*
X211622D01*
Y-382765D02*
Y-378435D01*
X209260Y-382765D02*
Y-378435D01*
X217160Y-382765D02*
Y-378435D01*
X219522Y-382765D02*
Y-378435D01*
X217160D02*
X219522D01*
X217160Y-382765D02*
X219522D01*
X221460D02*
X223822D01*
X221460Y-378435D02*
X223822D01*
Y-382765D02*
Y-378435D01*
X221460Y-382765D02*
Y-378435D01*
X236760Y-382765D02*
X239122D01*
X236760Y-378435D02*
X239122D01*
Y-382765D02*
Y-378435D01*
X236760Y-382765D02*
Y-378435D01*
X240760Y-382765D02*
X243122D01*
X240760Y-378435D02*
X243122D01*
Y-382765D02*
Y-378435D01*
X240760Y-382765D02*
Y-378435D01*
X252260Y-382765D02*
X254622D01*
X252260Y-378435D02*
X254622D01*
Y-382765D02*
Y-378435D01*
X252260Y-382765D02*
Y-378435D01*
X255760Y-382765D02*
Y-378435D01*
X258122Y-382765D02*
Y-378435D01*
X255760D02*
X258122D01*
X255760Y-382765D02*
X258122D01*
X268260D02*
X270622D01*
X268260Y-378435D02*
X270622D01*
Y-382765D02*
Y-378435D01*
X268260Y-382765D02*
Y-378435D01*
X110177Y-261761D02*
X116673D01*
X110177Y-265502D02*
X116673D01*
X110177D02*
Y-261761D01*
X116673Y-265502D02*
Y-261761D01*
X130905Y-344094D02*
X135236D01*
X130905Y-341732D02*
X135236D01*
Y-344094D02*
Y-341732D01*
X130905Y-344094D02*
Y-341732D01*
X572895Y-222339D02*
X576227Y-219007D01*
Y-222339D02*
X572895Y-219007D01*
X574561Y-222339D02*
Y-219007D01*
X576227Y-220673D02*
X572895D01*
X561721Y-280946D02*
X565053Y-277614D01*
Y-280946D02*
X561721Y-277614D01*
X563387Y-280946D02*
Y-277614D01*
X565053Y-279280D02*
X561721D01*
D21*
X572896Y-223390D02*
X596696D01*
X572896D02*
Y-203490D01*
X596696D01*
Y-223390D02*
Y-203490D01*
X572896Y-218390D02*
X577896Y-223390D01*
X561722Y-281997D02*
X585522D01*
X561722D02*
Y-262097D01*
X585522D01*
Y-281997D02*
Y-262097D01*
X561722Y-276997D02*
X566722Y-281997D01*
M02*
